G04 ================== begin FILE IDENTIFICATION RECORD ==================*
G04 Layout Name:  9049_F0T_FAN_BOARD_MP5048_D_v02_20221209_0830.brd*
G04 Film Name:    gnd*
G04 File Format:  Gerber RS274X*
G04 File Origin:  Cadence Allegro 17.2-S081*
G04 Origin Date:  Mon Dec 12 15:05:04 2022*
G04 *
G04 Layer:  DRAWING FORMAT/TITLE_BLOCK_A*
G04 Layer:  PIN/SPECIAL_DRILL*
G04 Layer:  DRAWING FORMAT/TITLE_BLOCK*
G04 Layer:  VIA CLASS/GND*
G04 Layer:  PIN/GND*
G04 Layer:  MANUFACTURING/PHOTOPLOT_OUTLINE*
G04 Layer:  ETCH/GND*
G04 Layer:  DRAWING FORMAT/TITLE_DATA_GND*
G04 *
G04 Offset:    (0.00 0.00)*
G04 Mirror:    No*
G04 Mode:      Negative*
G04 Rotation:  0*
G04 FullContactRelief:  No*
G04 UndefLineWidth:     6.00*
G04 ================== end FILE IDENTIFICATION RECORD ====================*
%FSLAX25Y25*MOIN*%
%IR0*IPPOS*OFA0.00000B0.00000*MIA0B0*SFA1.00000B1.00000*%
%AMMACRO26*
4,1,46,.05906,.17844,
.059724,.155545,
.06128,.13665,
.09787,-.20608,
.098198,-.223234,
.095542,-.240184,
.089983,-.256415,
.081691,-.271435,
.070916,-.284786,
.057986,-.296063,
.043294,-.304924,
.027287,-.311099,
.010451,-.314401,
-.006703,-.314729,
-.023653,-.312073,
-.039884,-.306514,
-.054904,-.298221,
-.068255,-.287446,
-.079532,-.274517,
-.088393,-.259825,
-.094568,-.243818,
-.09787,-.226982,
-.098198,-.209828,
-.09787,-.20608,
-.06128,.13665,
-.059515,.159487,
-.05906,.17844,
-.05906,.25591,
-.058163,.266166,
-.055498,.27611,
-.051147,.28544,
-.045243,.293873,
-.037963,.301153,
-.02953,.307057,
-.0202,.311408,
-.010256,.314073,
0.0,.31497,
.010256,.314073,
.0202,.311408,
.02953,.307057,
.037963,.301153,
.045243,.293873,
.051147,.28544,
.055498,.27611,
.058163,.266166,
.05906,.25591,
.05906,.17844,
0.0*
%
%ADD26MACRO26*%
%ADD17C,.03*%
%AMMACRO27*
4,1,36,0.0,.005,
.000868,.004924,
.00171,.004698,
.0025,.00433,
.003214,.00383,
.00383,.003214,
.00433,.0025,
.004698,.00171,
.004924,.000868,
.005,0.0,
.004924,-.000868,
.004698,-.00171,
.00433,-.0025,
.00383,-.003214,
.003214,-.00383,
.0025,-.00433,
.00171,-.004698,
.000868,-.004924,
0.0,-.005,
-.000868,-.004924,
-.00171,-.004698,
-.0025,-.00433,
-.003214,-.00383,
-.00383,-.003214,
-.00433,-.0025,
-.004698,-.00171,
-.004924,-.000868,
-.005,0.0,
-.004924,.000868,
-.004698,.00171,
-.00433,.0025,
-.00383,.003214,
-.003214,.00383,
-.0025,.00433,
-.00171,.004698,
-.000868,.004924,
0.0,.005,
0.0*
%
%ADD27MACRO27*%
%AMMACRO29*
4,1,36,.0025,0.0,
.002462,.000434,
.002349,.000855,
.002165,.00125,
.001915,.001607,
.001607,.001915,
.00125,.002165,
.000855,.002349,
.000434,.002462,
0.0,.0025,
-.000434,.002462,
-.000855,.002349,
-.00125,.002165,
-.001607,.001915,
-.001915,.001607,
-.002165,.00125,
-.002349,.000855,
-.002462,.000434,
-.0025,0.0,
-.002462,-.000434,
-.002349,-.000855,
-.002165,-.00125,
-.001915,-.001607,
-.001607,-.001915,
-.00125,-.002165,
-.000855,-.002349,
-.000434,-.002462,
0.0,-.0025,
.000434,-.002462,
.000855,-.002349,
.00125,-.002165,
.001607,-.001915,
.001915,-.001607,
.002165,-.00125,
.002349,-.000855,
.002462,-.000434,
.0025,0.0,
270.*
%
%ADD29MACRO29*%
%AMMACRO24*
4,1,36,.0025,0.0,
.002462,.000434,
.002349,.000855,
.002165,.00125,
.001915,.001607,
.001607,.001915,
.00125,.002165,
.000855,.002349,
.000434,.002462,
0.0,.0025,
-.000434,.002462,
-.000855,.002349,
-.00125,.002165,
-.001607,.001915,
-.001915,.001607,
-.002165,.00125,
-.002349,.000855,
-.002462,.000434,
-.0025,0.0,
-.002462,-.000434,
-.002349,-.000855,
-.002165,-.00125,
-.001915,-.001607,
-.001607,-.001915,
-.00125,-.002165,
-.000855,-.002349,
-.000434,-.002462,
0.0,-.0025,
.000434,-.002462,
.000855,-.002349,
.00125,-.002165,
.001607,-.001915,
.001915,-.001607,
.002165,-.00125,
.002349,-.000855,
.002462,-.000434,
.0025,0.0,
180.*
%
%ADD24MACRO24*%
%AMMACRO25*
4,1,36,-.0025,0.0,
-.002462,.000434,
-.002349,.000855,
-.002165,.00125,
-.001915,.001607,
-.001607,.001915,
-.00125,.002165,
-.000855,.002349,
-.000434,.002462,
0.0,.0025,
.000434,.002462,
.000855,.002349,
.00125,.002165,
.001607,.001915,
.001915,.001607,
.002165,.00125,
.002349,.000855,
.002462,.000434,
.0025,0.0,
.002462,-.000434,
.002349,-.000855,
.002165,-.00125,
.001915,-.001607,
.001607,-.001915,
.00125,-.002165,
.000855,-.002349,
.000434,-.002462,
0.0,-.0025,
-.000434,-.002462,
-.000855,-.002349,
-.00125,-.002165,
-.001607,-.001915,
-.001915,-.001607,
-.002165,-.00125,
-.002349,-.000855,
-.002462,-.000434,
-.0025,0.0,
180.*
%
%ADD25MACRO25*%
%AMMACRO23*
4,1,36,-.0025,0.0,
-.002462,.000434,
-.002349,.000855,
-.002165,.00125,
-.001915,.001607,
-.001607,.001915,
-.00125,.002165,
-.000855,.002349,
-.000434,.002462,
0.0,.0025,
.000434,.002462,
.000855,.002349,
.00125,.002165,
.001607,.001915,
.001915,.001607,
.002165,.00125,
.002349,.000855,
.002462,.000434,
.0025,0.0,
.002462,-.000434,
.002349,-.000855,
.002165,-.00125,
.001915,-.001607,
.001607,-.001915,
.00125,-.002165,
.000855,-.002349,
.000434,-.002462,
0.0,-.0025,
-.000434,-.002462,
-.000855,-.002349,
-.00125,-.002165,
-.001607,-.001915,
-.001915,-.001607,
-.002165,-.00125,
-.002349,-.000855,
-.002462,-.000434,
-.0025,0.0,
270.*
%
%ADD23MACRO23*%
%ADD21C,.058*%
%ADD12C,.087*%
%ADD20C,.089*%
%AMMACRO30*
4,1,18,.10783,.07955,
.120006,.059617,
.128535,.037873,
.133159,.014977,
.133736,-.008373,
.130251,-.031469,
.122807,-.053609,
.111633,-.074119,
.10783,-.07955,
.11284,-.08455,
.125808,-.063671,
.134953,-.040857,
.139997,-.016802,
.140788,.007763,
.137301,.032093,
.129642,.055447,
.118045,.077117,
.11284,.08455,
.10783,.07955,
0.0*
4,1,18,.07955,-.10783,
.059617,-.120006,
.037873,-.128535,
.014977,-.133159,
-.008373,-.133736,
-.031469,-.130251,
-.053609,-.122807,
-.074119,-.111633,
-.07955,-.10783,
-.08455,-.11284,
-.063671,-.125808,
-.040857,-.134953,
-.016802,-.139997,
.007763,-.140788,
.032093,-.137301,
.055447,-.129642,
.077117,-.118045,
.08455,-.11284,
.07955,-.10783,
0.0*
4,1,18,-.10783,-.07955,
-.120006,-.059617,
-.128535,-.037873,
-.133159,-.014977,
-.133736,.008373,
-.130251,.031469,
-.122807,.053609,
-.111633,.074119,
-.10783,.07955,
-.11284,.08455,
-.125808,.063671,
-.134953,.040857,
-.139997,.016802,
-.140788,-.007763,
-.137301,-.032093,
-.129642,-.055447,
-.118045,-.077117,
-.11284,-.08455,
-.10783,-.07955,
0.0*
4,1,18,-.07955,.10783,
-.059617,.120006,
-.037873,.128535,
-.014977,.133159,
.008373,.133736,
.031469,.130251,
.053609,.122807,
.074119,.111633,
.07955,.10783,
.08455,.11284,
.063671,.125808,
.040857,.134953,
.016802,.139997,
-.007763,.140788,
-.032093,.137301,
-.055447,.129642,
-.077117,.118045,
-.08455,.11284,
-.07955,.10783,
0.0*
%
%ADD30MACRO30*%
%AMMACRO31*
4,1,15,-.02364,.01304,
-.025545,.008737,
-.026674,.004168,
-.026993,-.000527,
-.026491,-.005206,
-.025185,-.009727,
-.02364,-.01304,
-.02875,-.01815,
-.031465,-.012882,
-.033224,-.007222,
-.033973,-.001343,
-.03369,.004576,
-.032384,.010357,
-.030093,.015823,
-.02875,.01815,
-.02364,.01304,
90.*
4,1,15,-.01304,-.02364,
-.008737,-.025545,
-.004168,-.026674,
.000527,-.026993,
.005206,-.026491,
.009727,-.025185,
.01304,-.02364,
.01815,-.02875,
.012882,-.031465,
.007222,-.033224,
.001343,-.033973,
-.004576,-.03369,
-.010357,-.032384,
-.015823,-.030093,
-.01815,-.02875,
-.01304,-.02364,
90.*
4,1,15,.02364,-.01304,
.025545,-.008737,
.026674,-.004168,
.026993,.000527,
.026491,.005206,
.025185,.009727,
.02364,.01304,
.02875,.01815,
.031465,.012882,
.033224,.007222,
.033973,.001343,
.03369,-.004576,
.032384,-.010357,
.030093,-.015823,
.02875,-.01815,
.02364,-.01304,
90.*
4,1,15,.01304,.02364,
.008737,.025545,
.004168,.026674,
-.000527,.026993,
-.005206,.026491,
-.009727,.025185,
-.01304,.02364,
-.01815,.02875,
-.012882,.031465,
-.007222,.033224,
-.001343,.033973,
.004576,.03369,
.010357,.032384,
.015823,.030093,
.01815,.02875,
.01304,.02364,
90.*
%
%ADD31MACRO31*%
%AMMACRO14*
4,1,15,.03682,.01914,
.039584,.012455,
.041146,.005393,
.041457,-.001834,
.040509,-.009005,
.03833,-.015903,
.03682,-.01914,
.04197,-.0243,
.045552,-.016643,
.04775,-.00848,
.048497,-.000059,
.047771,.008363,
.045593,.016531,
.042029,.024197,
.04197,.0243,
.03682,.01914,
0.0*
4,1,15,.01914,-.03682,
.012455,-.039584,
.005393,-.041146,
-.001834,-.041457,
-.009005,-.040509,
-.015903,-.03833,
-.01914,-.03682,
-.0243,-.04197,
-.016643,-.045552,
-.00848,-.04775,
-.000059,-.048497,
.008363,-.047771,
.016531,-.045593,
.024197,-.042029,
.0243,-.04197,
.01914,-.03682,
0.0*
4,1,15,-.03682,-.01914,
-.039584,-.012455,
-.041146,-.005393,
-.041457,.001834,
-.040509,.009005,
-.03833,.015903,
-.03682,.01914,
-.04197,.0243,
-.045552,.016643,
-.04775,.00848,
-.048497,.000059,
-.047771,-.008363,
-.045593,-.016531,
-.042029,-.024197,
-.04197,-.0243,
-.03682,-.01914,
0.0*
4,1,15,-.01914,.03682,
-.012455,.039584,
-.005393,.041146,
.001834,.041457,
.009005,.040509,
.015903,.03833,
.01914,.03682,
.0243,.04197,
.016643,.045552,
.00848,.04775,
.000059,.048497,
-.008363,.047771,
-.016531,.045593,
-.024197,.042029,
-.0243,.04197,
-.01914,.03682,
0.0*
%
%ADD14MACRO14*%
%AMMACRO11*
4,1,15,-.03682,.01914,
-.039584,.012455,
-.041146,.005393,
-.041457,-.001834,
-.040509,-.009005,
-.03833,-.015903,
-.03682,-.01914,
-.04197,-.0243,
-.045552,-.016643,
-.04775,-.00848,
-.048497,-.000059,
-.047771,.008363,
-.045593,.016531,
-.042029,.024197,
-.04197,.0243,
-.03682,.01914,
0.0*
4,1,15,-.01914,-.03682,
-.012455,-.039584,
-.005393,-.041146,
.001834,-.041457,
.009005,-.040509,
.015903,-.03833,
.01914,-.03682,
.0243,-.04197,
.016643,-.045552,
.00848,-.04775,
.000059,-.048497,
-.008363,-.047771,
-.016531,-.045593,
-.024197,-.042029,
-.0243,-.04197,
-.01914,-.03682,
0.0*
4,1,15,.03682,-.01914,
.039584,-.012455,
.041146,-.005393,
.041457,.001834,
.040509,.009005,
.03833,.015903,
.03682,.01914,
.04197,.0243,
.045552,.016643,
.04775,.00848,
.048497,.000059,
.047771,-.008363,
.045593,-.016531,
.042029,-.024197,
.04197,-.0243,
.03682,-.01914,
0.0*
4,1,15,.01914,.03682,
.012455,.039584,
.005393,.041146,
-.001834,.041457,
-.009005,.040509,
-.015903,.03833,
-.01914,.03682,
-.0243,.04197,
-.016643,.045552,
-.00848,.04775,
-.000059,.048497,
.008363,.047771,
.016531,.045593,
.024197,.042029,
.0243,.04197,
.01914,.03682,
0.0*
%
%ADD11MACRO11*%
%ADD10C,.125*%
%ADD28C,.155*%
%AMMACRO16*
4,1,36,.0025,0.0,
.002462,.000434,
.002349,.000855,
.002165,.00125,
.001915,.001607,
.001607,.001915,
.00125,.002165,
.000855,.002349,
.000434,.002462,
0.0,.0025,
-.000434,.002462,
-.000855,.002349,
-.00125,.002165,
-.001607,.001915,
-.001915,.001607,
-.002165,.00125,
-.002349,.000855,
-.002462,.000434,
-.0025,0.0,
-.002462,-.000434,
-.002349,-.000855,
-.002165,-.00125,
-.001915,-.001607,
-.001607,-.001915,
-.00125,-.002165,
-.000855,-.002349,
-.000434,-.002462,
0.0,-.0025,
.000434,-.002462,
.000855,-.002349,
.00125,-.002165,
.001607,-.001915,
.001915,-.001607,
.002165,-.00125,
.002349,-.000855,
.002462,-.000434,
.0025,0.0,
90.*
%
%ADD16MACRO16*%
%AMMACRO18*
4,1,36,.0025,0.0,
.002462,.000434,
.002349,.000855,
.002165,.00125,
.001915,.001607,
.001607,.001915,
.00125,.002165,
.000855,.002349,
.000434,.002462,
0.0,.0025,
-.000434,.002462,
-.000855,.002349,
-.00125,.002165,
-.001607,.001915,
-.001915,.001607,
-.002165,.00125,
-.002349,.000855,
-.002462,.000434,
-.0025,0.0,
-.002462,-.000434,
-.002349,-.000855,
-.002165,-.00125,
-.001915,-.001607,
-.001607,-.001915,
-.00125,-.002165,
-.000855,-.002349,
-.000434,-.002462,
0.0,-.0025,
.000434,-.002462,
.000855,-.002349,
.00125,-.002165,
.001607,-.001915,
.001915,-.001607,
.002165,-.00125,
.002349,-.000855,
.002462,-.000434,
.0025,0.0,
0.0*
%
%ADD18MACRO18*%
%AMMACRO19*
4,1,36,-.0025,0.0,
-.002462,.000434,
-.002349,.000855,
-.002165,.00125,
-.001915,.001607,
-.001607,.001915,
-.00125,.002165,
-.000855,.002349,
-.000434,.002462,
0.0,.0025,
.000434,.002462,
.000855,.002349,
.00125,.002165,
.001607,.001915,
.001915,.001607,
.002165,.00125,
.002349,.000855,
.002462,.000434,
.0025,0.0,
.002462,-.000434,
.002349,-.000855,
.002165,-.00125,
.001915,-.001607,
.001607,-.001915,
.00125,-.002165,
.000855,-.002349,
.000434,-.002462,
0.0,-.0025,
-.000434,-.002462,
-.000855,-.002349,
-.00125,-.002165,
-.001607,-.001915,
-.001915,-.001607,
-.002165,-.00125,
-.002349,-.000855,
-.002462,-.000434,
-.0025,0.0,
0.0*
%
%ADD19MACRO19*%
%AMMACRO22*
4,1,15,-.02364,.01304,
-.025545,.008737,
-.026674,.004168,
-.026993,-.000527,
-.026491,-.005206,
-.025185,-.009727,
-.02364,-.01304,
-.02875,-.01815,
-.031465,-.012882,
-.033224,-.007222,
-.033973,-.001343,
-.03369,.004576,
-.032384,.010357,
-.030093,.015823,
-.02875,.01815,
-.02364,.01304,
270.*
4,1,15,-.01304,-.02364,
-.008737,-.025545,
-.004168,-.026674,
.000527,-.026993,
.005206,-.026491,
.009727,-.025185,
.01304,-.02364,
.01815,-.02875,
.012882,-.031465,
.007222,-.033224,
.001343,-.033973,
-.004576,-.03369,
-.010357,-.032384,
-.015823,-.030093,
-.01815,-.02875,
-.01304,-.02364,
270.*
4,1,15,.02364,-.01304,
.025545,-.008737,
.026674,-.004168,
.026993,.000527,
.026491,.005206,
.025185,.009727,
.02364,.01304,
.02875,.01815,
.031465,.012882,
.033224,.007222,
.033973,.001343,
.03369,-.004576,
.032384,-.010357,
.030093,-.015823,
.02875,-.01815,
.02364,-.01304,
270.*
4,1,15,.01304,.02364,
.008737,.025545,
.004168,.026674,
-.000527,.026993,
-.005206,.026491,
-.009727,.025185,
-.01304,.02364,
-.01815,.02875,
-.012882,.031465,
-.007222,.033224,
-.001343,.033973,
.004576,.03369,
.010357,.032384,
.015823,.030093,
.01815,.02875,
.01304,.02364,
270.*
%
%ADD22MACRO22*%
%AMMACRO13*
4,1,15,.03682,.01914,
.039584,.012455,
.041146,.005393,
.041457,-.001834,
.040509,-.009005,
.03833,-.015903,
.03682,-.01914,
.04197,-.0243,
.045552,-.016643,
.04775,-.00848,
.048497,-.000059,
.047771,.008363,
.045593,.016531,
.042029,.024197,
.04197,.0243,
.03682,.01914,
180.*
4,1,15,.01914,-.03682,
.012455,-.039584,
.005393,-.041146,
-.001834,-.041457,
-.009005,-.040509,
-.015903,-.03833,
-.01914,-.03682,
-.0243,-.04197,
-.016643,-.045552,
-.00848,-.04775,
-.000059,-.048497,
.008363,-.047771,
.016531,-.045593,
.024197,-.042029,
.0243,-.04197,
.01914,-.03682,
180.*
4,1,15,-.03682,-.01914,
-.039584,-.012455,
-.041146,-.005393,
-.041457,.001834,
-.040509,.009005,
-.03833,.015903,
-.03682,.01914,
-.04197,.0243,
-.045552,.016643,
-.04775,.00848,
-.048497,.000059,
-.047771,-.008363,
-.045593,-.016531,
-.042029,-.024197,
-.04197,-.0243,
-.03682,-.01914,
180.*
4,1,15,-.01914,.03682,
-.012455,.039584,
-.005393,.041146,
.001834,.041457,
.009005,.040509,
.015903,.03833,
.01914,.03682,
.0243,.04197,
.016643,.045552,
.00848,.04775,
.000059,.048497,
-.008363,.047771,
-.016531,.045593,
-.024197,.042029,
-.0243,.04197,
-.01914,.03682,
180.*
%
%ADD13MACRO13*%
%AMMACRO15*
4,1,15,-.03682,.01914,
-.039584,.012455,
-.041146,.005393,
-.041457,-.001834,
-.040509,-.009005,
-.03833,-.015903,
-.03682,-.01914,
-.04197,-.0243,
-.045552,-.016643,
-.04775,-.00848,
-.048497,-.000059,
-.047771,.008363,
-.045593,.016531,
-.042029,.024197,
-.04197,.0243,
-.03682,.01914,
180.*
4,1,15,-.01914,-.03682,
-.012455,-.039584,
-.005393,-.041146,
.001834,-.041457,
.009005,-.040509,
.015903,-.03833,
.01914,-.03682,
.0243,-.04197,
.016643,-.045552,
.00848,-.04775,
.000059,-.048497,
-.008363,-.047771,
-.016531,-.045593,
-.024197,-.042029,
-.0243,-.04197,
-.01914,-.03682,
180.*
4,1,15,.03682,-.01914,
.039584,-.012455,
.041146,-.005393,
.041457,.001834,
.040509,.009005,
.03833,.015903,
.03682,.01914,
.04197,.0243,
.045552,.016643,
.04775,.00848,
.048497,.000059,
.047771,-.008363,
.045593,-.016531,
.042029,-.024197,
.04197,-.0243,
.03682,-.01914,
180.*
4,1,15,.01914,.03682,
.012455,.039584,
.005393,.041146,
-.001834,.041457,
-.009005,.040509,
-.015903,.03833,
-.01914,.03682,
-.0243,.04197,
-.016643,.045552,
-.00848,.04775,
-.000059,.048497,
.008363,.047771,
.016531,.045593,
.024197,.042029,
.0243,.04197,
.01914,.03682,
180.*
%
%ADD15MACRO15*%
%ADD32C,.006*%
%ADD37C,.07*%
%ADD36C,.07006*%
%ADD34C,.09906*%
%ADD35C,.10406*%
%ADD33C,.16506*%
G75*
%LPD*%
G75*
G36*
G01X-320500Y-470483D02*
X2967000D01*
Y2626000D01*
X-320500D01*
Y-470483D01*
G37*
%LPC*%
G75*
G36*
G01X-70000Y602000D02*
G02X-75874Y607874I0J5874D01*
G01Y1318898D01*
G02X-70000Y1324772I5874J0D01*
G01X-15748D01*
G02X-9874Y1318898I0J-5874D01*
G01Y607874D01*
G02X-15748Y602000I-5874J0D01*
G01X-70000D01*
G37*
G36*
G01X15748Y1324768D02*
X187795D01*
G02X201539Y1311024I0J-13744D01*
G01Y15748D01*
G02X187795Y2004I-13744J0D01*
G01X145559D01*
G02X145417Y2063I0J200D01*
G01X140803Y6677D01*
G02X140744Y6819I141J142D01*
G01Y43307D01*
G03X127287I-6729J0D01*
G01Y32285D01*
G02X127087Y32085I-200J0D01*
G01X110354D01*
G02X110154Y32285I0J200D01*
G01Y36019D01*
G02X110231Y36177I200J0D01*
G01X110518Y36400D01*
X110608Y36419D01*
X110653Y36407D01*
G03X111522Y36298I867J3393D01*
G03X112941Y36598I1J3502D01*
G02X113103I81J-183D01*
G03X114522Y36298I1418J3202D01*
G03X118024Y39800I0J3502D01*
G03X117819Y40982I-3502J1D01*
G02Y41118I188J68D01*
G03X118024Y42300I-3297J1181D01*
G03X117819Y43482I-3502J1D01*
G02Y43618I188J68D01*
G03X118024Y44800I-3297J1181D01*
G03X117819Y45982I-3502J1D01*
G02Y46118I188J68D01*
G03X118024Y47300I-3297J1181D01*
G03X117819Y48482I-3502J1D01*
G02Y48618I188J68D01*
G03X118024Y49800I-3297J1181D01*
G03X117819Y50982I-3502J1D01*
G02Y51118I188J68D01*
G03X118024Y52300I-3297J1181D01*
G03X114522Y55802I-3502J0D01*
G03X113103Y55502I-1J-3502D01*
G02X112941I-81J183D01*
G03X111522Y55802I-1418J-3202D01*
G03X108020Y52300I0J-3502D01*
G03X108225Y51118I3502J-1D01*
G02Y50982I-188J-68D01*
G03X108020Y49800I3297J-1181D01*
G03X108225Y48618I3502J-1D01*
G02Y48482I-188J-68D01*
G03X108020Y47300I3297J-1181D01*
G03X108031Y47022I3502J-1D01*
G01X108034Y46973D01*
X107998Y46886D01*
X107680Y46612D01*
X107588Y46589D01*
X107541Y46600D01*
G03X106772Y46689I-771J-3293D01*
G03X103390Y43307I0J-3382D01*
G01Y32285D01*
G02X103190Y32085I-200J0D01*
G01X76456D01*
G02X76256Y32285I0J200D01*
G01Y43307D01*
G03X62799I-6729J0D01*
G01Y6819D01*
G02X62740Y6677I-200J0D01*
G01X58126Y2063D01*
G02X57984Y2004I-142J141D01*
G01X15748D01*
G02X2004Y15748I0J13744D01*
G01Y1039281D01*
X2000D01*
Y1040354D01*
X2004D01*
Y1311024D01*
G02X15748Y1324768I13744J0D01*
G37*
%LPD*%
G75*
G36*
G01X143818Y63294D02*
G02X145000Y63500I1183J-3294D01*
G02X146182Y63294I-1J-3500D01*
G03X146318I68J188D01*
G02X147500Y63500I1183J-3294D01*
G02X151000Y60000I0J-3500D01*
G02X150794Y58818I-3500J1D01*
G03Y58682I188J-68D01*
G02X151000Y57500I-3294J-1183D01*
G02X150794Y56318I-3500J1D01*
G03Y56182I188J-68D01*
G02X151000Y55000I-3294J-1183D01*
G02X147500Y51500I-3500J0D01*
G02X146318Y51706I1J3500D01*
G03X146182I-68J-188D01*
G02X145000Y51500I-1183J3294D01*
G02X143818Y51706I1J3500D01*
G03X143682I-68J-188D01*
G02X142500Y51500I-1183J3294D01*
G02X139143Y54008I0J3501D01*
G03X139008Y54143I-191J-56D01*
G02X138818Y54206I1006J3352D01*
G03X138682I-68J-188D01*
G02X137500Y54000I-1183J3294D01*
G02X134000Y57500I0J3500D01*
G02X134206Y58682I3500J-1D01*
G03Y58818I-188J68D01*
G02X134000Y60000I3294J1183D01*
G02X137500Y63500I3500J0D01*
G02X138682Y63294I-1J-3500D01*
G03X138818I68J188D01*
G02X140000Y63500I1183J-3294D01*
G02X141182Y63294I-1J-3500D01*
G03X141318I68J188D01*
G02X142500Y63500I1183J-3294D01*
G02X143682Y63294I-1J-3500D01*
G03X143818I68J188D01*
G37*
G36*
G01X78800Y77127D02*
X78832Y77242D01*
G03X78818Y77389I-192J56D01*
G02X78425Y79000I3107J1611D01*
G02X85425I3500J0D01*
G02X83716Y75993I-3500J0D01*
G03X83626Y75876I102J-172D01*
G01X83593Y75761D01*
G03X83608Y75614I193J-55D01*
G02X84002Y74000I-3109J-1614D01*
G02X76998I-3502J0D01*
G02X78710Y77010I3502J0D01*
G03X78800Y77127I-103J172D01*
G37*
G36*
G01X136200Y97805D02*
X135800Y97705D01*
X135731Y97646D01*
X135712Y97603D01*
G02X132500Y95498I-3212J1398D01*
G02Y102502I0J3502D01*
G02X134676Y101744I0J-3502D01*
G01X134713Y101715D01*
X134803Y101696D01*
X135203Y101795D01*
X135272Y101855D01*
X135291Y101898D01*
G02X138500Y104000I3209J-1398D01*
G02Y97000I0J-3500D01*
G02X136327Y97756I0J3501D01*
G01X136290Y97786D01*
X136200Y97805D01*
G37*
G36*
G01X125844Y103232D02*
G02X128000Y100000I-1345J-3232D01*
G02X124500Y96500I-3500J0D01*
G02X121268Y98656I0J3501D01*
G03X121160Y98764I-185J-77D01*
G02X118998Y102000I1341J3236D01*
G02X122500Y105502I3502J0D01*
G02X125736Y103340I0J-3503D01*
G03X125844Y103232I185J77D01*
G37*
G36*
G01X74190Y118924D02*
G02X77518Y121342I3328J-1081D01*
G02X81018Y117842I0J-3500D01*
G02X80119Y115500I-3500J0D01*
G03X80077Y115427I148J-134D01*
G02X76743Y112998I-3334J1074D01*
G02X73240Y116500I-1J3502D01*
G02X74148Y118852I3503J-1D01*
G03X74190Y118924I-148J135D01*
G37*
G36*
G01X145279Y147967D02*
G02X145074Y149149I3297J1181D01*
G02X148576Y152652I3502J1D01*
G02X149995Y152351I-2J-3503D01*
G03X150157I81J183D01*
G02X151576Y152652I1421J-3202D01*
G02X152995Y152351I-2J-3503D01*
G03X153157I81J183D01*
G02X154576Y152652I1421J-3202D01*
G02X158078Y149149I-1J-3503D01*
G02X157873Y147967I-3502J-1D01*
G03Y147831I188J-68D01*
G02X158078Y146649I-3297J-1181D01*
G02X154576Y143146I-3502J-1D01*
G02X153157Y143447I2J3503D01*
G03X152995I-81J-183D01*
G02X151576Y143146I-1421J3202D01*
G02X150157Y143447I2J3503D01*
G03X149995I-81J-183D01*
G02X148576Y143146I-1421J3202D01*
G02X145074Y146649I1J3503D01*
G02X145279Y147831I3502J1D01*
G03Y147967I-188J68D01*
G37*
G36*
G01X41157Y148340D02*
G02X40896Y149664I3241J1327D01*
G02X41102Y150846I3503J-2D01*
G03Y150982I-188J68D01*
G02X40896Y152164I3297J1184D01*
G02X44399Y155666I3503J-1D01*
G02X45818Y155366I1J-3502D01*
G03X45980I81J183D01*
G02X47399Y155666I1418J-3202D01*
G02X50902Y152164I1J-3502D01*
G02X50696Y150982I-3503J2D01*
G03Y150846I188J-68D01*
G02X50902Y149664I-3297J-1184D01*
G02X50641Y148340I-3502J3D01*
G03Y148188I186J-76D01*
G02X50902Y146864I-3241J-1327D01*
G02X47399Y143362I-3503J1D01*
G02X45980Y143662I-1J3502D01*
G03X45818I-81J-183D01*
G02X44399Y143362I-1418J3202D01*
G02X40896Y146864I-1J3502D01*
G02X41157Y148188I3502J-3D01*
G03Y148340I-186J76D01*
G37*
G36*
G01X45906Y168062D02*
G02X44487Y167762I-1418J3202D01*
G02X40984Y171264I-1J3502D01*
G02X41285Y172683I3503J-2D01*
G03Y172845I-183J81D01*
G02X40984Y174264I3202J1421D01*
G02X44487Y177766I3503J-1D01*
G02X45906Y177466I1J-3502D01*
G03X46068I81J183D01*
G02X47487Y177766I1418J-3202D01*
G02X50990Y174264I1J-3502D01*
G02X50689Y172845I-3503J2D01*
G03Y172683I183J-81D01*
G02X50990Y171264I-3202J-1421D01*
G02X47487Y167762I-3503J1D01*
G02X46068Y168062I-1J3502D01*
G03X45906I-81J-183D01*
G37*
G36*
G01X146462Y170024D02*
G02X146162Y171443I3202J1418D01*
G02X146462Y172862I3502J1D01*
G03Y173024I-183J81D01*
G02X146162Y174443I3202J1418D01*
G02X153166I3502J0D01*
G02X152866Y173024I-3502J-1D01*
G03Y172862I183J-81D01*
G02X153166Y171443I-3202J-1418D01*
G02X152866Y170024I-3502J-1D01*
G03Y169862I183J-81D01*
G02X153166Y168443I-3202J-1418D01*
G02X152866Y167024I-3502J-1D01*
G03Y166862I183J-81D01*
G02X153166Y165443I-3202J-1418D01*
G02X146162I-3502J0D01*
G02X146462Y166862I3502J1D01*
G03Y167024I-183J81D01*
G02X146162Y168443I3202J1418D01*
G02X146462Y169862I3502J1D01*
G03Y170024I-183J81D01*
G37*
G36*
G01X32715Y196218D02*
G02X30978Y199243I1766J3025D01*
G02X31278Y200662I3502J1D01*
G03Y200824I-183J81D01*
G02X30978Y202243I3202J1418D01*
G02X37982I3502J0D01*
G02X37682Y200824I-3502J-1D01*
G03Y200662I183J-81D01*
G02X37982Y199243I-3202J-1418D01*
G02X36303Y196252I-3502J-1D01*
G01X36257Y196224D01*
X36206Y196133D01*
X36211Y195682D01*
X36263Y195592D01*
X36309Y195565D01*
G02X38046Y192540I-1766J-3025D01*
G02X37746Y191121I-3502J-1D01*
G03Y190959I183J-81D01*
G02X38046Y189540I-3202J-1418D01*
G02X36108Y186406I-3503J0D01*
G01X36057Y186381D01*
X35999Y186288D01*
X35987Y185822D01*
X36042Y185727D01*
X36091Y185699D01*
G02X37882Y182643I-1712J-3056D01*
G02X37582Y181224I-3502J-1D01*
G03Y181062I183J-81D01*
G02X37882Y179643I-3202J-1418D01*
G02X30878I-3502J0D01*
G02X31178Y181062I3502J1D01*
G03Y181224I-183J81D01*
G02X30878Y182643I3202J1418D01*
G02X32816Y185777I3503J0D01*
G01X32867Y185802D01*
X32925Y185895D01*
X32937Y186361D01*
X32882Y186456D01*
X32833Y186484D01*
G02X31042Y189540I1712J3056D01*
G02X31342Y190959I3502J1D01*
G03Y191121I-183J81D01*
G02X31042Y192540I3202J1418D01*
G02X32721Y195531I3502J1D01*
G01X32767Y195559D01*
X32818Y195650D01*
X32813Y196101D01*
X32761Y196191D01*
X32715Y196218D01*
G37*
G36*
G01X32393Y208847D02*
G02X32694Y207428I-3202J-1421D01*
G02X25688I-3503J0D01*
G02X25989Y208847I3503J-2D01*
G03Y209009I-183J81D01*
G02X25688Y210428I3202J1421D01*
G02X32694I3503J0D01*
G02X32393Y209009I-3503J2D01*
G03Y208847I183J-81D01*
G37*
G36*
G01X176156Y228909D02*
G02X175856Y230328I3202J1418D01*
G02X179358Y233830I3502J0D01*
G02X180777Y233530I1J-3502D01*
G03X180939I81J183D01*
G02X182358Y233830I1418J-3202D01*
G02X183777Y233530I1J-3502D01*
G03X183939I81J183D01*
G02X185358Y233830I1418J-3202D01*
G02X188860Y230328I0J-3502D01*
G02X188560Y228909I-3502J-1D01*
G03Y228747I183J-81D01*
G02X188860Y227328I-3202J-1418D01*
G02X185358Y223826I-3502J0D01*
G02X183939Y224126I-1J3502D01*
G03X183777I-81J-183D01*
G02X182358Y223826I-1418J3202D01*
G02X180939Y224126I-1J3502D01*
G03X180777I-81J-183D01*
G02X179358Y223826I-1418J3202D01*
G02X175856Y227328I0J3502D01*
G02X176156Y228747I3502J1D01*
G03Y228909I-183J81D01*
G37*
G36*
G01X164361Y233883D02*
G02X165562Y234096I1203J-3290D01*
G02Y227090I0J-3503D01*
G02X164361Y227303I2J3503D01*
G03X164223I-69J-188D01*
G02X163022Y227090I-1203J3290D01*
G02Y234096I0J3503D01*
G02X164223Y233883I-2J-3503D01*
G03X164361I69J188D01*
G37*
G36*
G01X44977Y233313D02*
G02X44974Y233457I3500J145D01*
G02X48477Y236960I3503J0D01*
G02X49896Y236659I-2J-3503D01*
G03X50058I81J183D01*
G02X51477Y236960I1421J-3202D01*
G02X52896Y236659I-2J-3503D01*
G03X53058I81J183D01*
G02X54477Y236960I1421J-3202D01*
G02X57980Y233457I0J-3503D01*
G02X57616Y231903I-3503J1D01*
G03X57615Y231728I179J-89D01*
G02X57958Y230214I-3160J-1512D01*
G02X54456Y226712I-3502J0D01*
G02X53037Y227012I-1J3502D01*
G03X52875I-81J-183D01*
G02X51456Y226712I-1418J3202D01*
G02X50037Y227012I-1J3502D01*
G03X49875I-81J-183D01*
G02X48456Y226712I-1418J3202D01*
G02X45629Y228146I-1J3502D01*
G01X45601Y228185D01*
X45516Y228228D01*
X45098Y228229D01*
X45013Y228186D01*
X44985Y228147D01*
G02X42167Y226726I-2817J2082D01*
G02X40748Y227026I-1J3502D01*
G03X40586I-81J-183D01*
G02X39167Y226726I-1418J3202D01*
G02Y233730I0J3502D01*
G02X40586Y233430I1J-3502D01*
G03X40748I81J183D01*
G02X42167Y233730I1418J-3202D01*
G02X44331Y232982I1J-3502D01*
G01X44377Y232946D01*
X44493Y232935D01*
X44921Y233154D01*
X44980Y233254D01*
X44977Y233313D01*
G37*
G36*
G01X181077Y240326D02*
G02X179658Y240026I-1418J3202D01*
G02Y247030I0J3502D01*
G02X181077Y246730I1J-3502D01*
G03X181239I81J183D01*
G02X182658Y247030I1418J-3202D01*
G02X184077Y246730I1J-3502D01*
G03X184239I81J183D01*
G02X185658Y247030I1418J-3202D01*
G02Y240026I0J-3502D01*
G02X184239Y240326I-1J3502D01*
G03X184077I-81J-183D01*
G02X182658Y240026I-1418J3202D01*
G02X181239Y240326I-1J3502D01*
G03X181077I-81J-183D01*
G37*
G36*
G01X52386Y243026D02*
G02X50967Y242726I-1418J3202D01*
G02Y249730I0J3502D01*
G02X52386Y249430I1J-3502D01*
G03X52548I81J183D01*
G02X53967Y249730I1418J-3202D01*
G02X55386Y249430I1J-3502D01*
G03X55548I81J183D01*
G02X56967Y249730I1418J-3202D01*
G02Y242726I0J-3502D01*
G02X55548Y243026I-1J3502D01*
G03X55386I-81J-183D01*
G02X53967Y242726I-1418J3202D01*
G02X52548Y243026I-1J3502D01*
G03X52386I-81J-183D01*
G37*
G36*
G01X19766Y318430D02*
G02X21185Y318730I1418J-3202D01*
G02X22604Y318430I1J-3502D01*
G03X22766I81J183D01*
G02X24185Y318730I1418J-3202D01*
G02X25604Y318430I1J-3502D01*
G03X25766I81J183D01*
G02X27185Y318730I1418J-3202D01*
G02X30688Y315228I1J-3502D01*
G02X30387Y313809I-3503J2D01*
G03Y313647I183J-81D01*
G02X30688Y312228I-3202J-1421D01*
G02X27185Y308726I-3503J1D01*
G02X25766Y309026I-1J3502D01*
G03X25604I-81J-183D01*
G02X24185Y308726I-1418J3202D01*
G02X22766Y309026I-1J3502D01*
G03X22604I-81J-183D01*
G02X21185Y308726I-1418J3202D01*
G02X19766Y309026I-1J3502D01*
G03X19604I-81J-183D01*
G02X18185Y308726I-1418J3202D01*
G02X14682Y312228I-1J3502D01*
G02X14983Y313647I3503J-2D01*
G03Y313809I-183J81D01*
G02X14682Y315228I3202J1421D01*
G02X18185Y318730I3503J-1D01*
G02X19604Y318430I1J-3502D01*
G03X19766I81J183D01*
G37*
G36*
G01X124280Y313809D02*
G02X123980Y315228I3202J1418D01*
G02X127482Y318730I3502J0D01*
G02X128901Y318430I1J-3502D01*
G03X129063I81J183D01*
G02X130482Y318730I1418J-3202D01*
G02X131901Y318430I1J-3502D01*
G03X132063I81J183D01*
G02X133482Y318730I1418J-3202D01*
G02X136984Y315228I0J-3502D01*
G02X136684Y313809I-3502J-1D01*
G03Y313647I183J-81D01*
G02X136984Y312228I-3202J-1418D01*
G02X133482Y308726I-3502J0D01*
G02X132063Y309026I-1J3502D01*
G03X131901I-81J-183D01*
G02X130482Y308726I-1418J3202D01*
G02X129063Y309026I-1J3502D01*
G03X128901I-81J-183D01*
G02X127482Y308726I-1418J3202D01*
G02X123980Y312228I0J3502D01*
G02X124280Y313647I3502J1D01*
G03Y313809I-183J81D01*
G37*
G36*
G01X38766Y319430D02*
G02X40185Y319730I1418J-3202D01*
G02Y312726I0J-3502D01*
G02X38766Y313026I-1J3502D01*
G03X38604I-81J-183D01*
G02X37185Y312726I-1418J3202D01*
G02Y319730I0J3502D01*
G02X38604Y319430I1J-3502D01*
G03X38766I81J183D01*
G37*
G36*
G01X148063D02*
G02X149482Y319730I1418J-3202D01*
G02Y312726I0J-3502D01*
G02X148063Y313026I-1J3502D01*
G03X147901I-81J-183D01*
G02X146482Y312726I-1418J3202D01*
G02Y319730I0J3502D01*
G02X147901Y319430I1J-3502D01*
G03X148063I81J183D01*
G37*
G36*
G01X162060Y330647D02*
G02X162360Y329228I-3202J-1418D01*
G02X155356I-3502J0D01*
G02X155656Y330647I3502J1D01*
G03Y330809I-183J81D01*
G02X155356Y332228I3202J1418D01*
G02X162360I3502J0D01*
G02X162060Y330809I-3502J-1D01*
G03Y330647I183J-81D01*
G37*
G36*
G01X147856Y338390D02*
G02X148102Y337100I-3256J-1289D01*
G02X141098I-3502J0D01*
G02X141344Y338390I3502J1D01*
G03Y338538I-186J74D01*
G02X141098Y339828I3256J1289D01*
G02X148102I3502J0D01*
G02X147856Y338538I-3502J-1D01*
G03Y338390I186J-74D01*
G37*
G36*
G01X49703Y347315D02*
G02X49498Y348497I3297J1181D01*
G02X49703Y349679I3502J1D01*
G03Y349815I-188J68D01*
G02X49498Y350997I3297J1181D01*
G02X56502I3502J0D01*
G02X56297Y349815I-3502J-1D01*
G03Y349679I188J-68D01*
G02X56502Y348497I-3297J-1181D01*
G02X56297Y347315I-3502J-1D01*
G03Y347179I188J-68D01*
G02X56502Y346061I-3297J-1182D01*
G03X56648Y345872I200J4D01*
G02X59202Y342500I-949J-3372D01*
G02X55700Y338998I-3502J0D01*
G02X52198Y342436I0J3503D01*
G03X52052Y342625I-200J-4D01*
G02X49498Y345997I949J3372D01*
G02X49703Y347179I3502J1D01*
G03Y347315I-188J68D01*
G37*
G36*
G01X146644Y347738D02*
G02X146398Y349028I3256J1289D01*
G02X146652Y350339I3502J2D01*
G03Y350489I-185J75D01*
G02X146398Y351800I3248J1309D01*
G02X153402I3502J0D01*
G02X153148Y350489I-3502J-2D01*
G03Y350339I185J-75D01*
G02X153402Y349028I-3248J-1309D01*
G02X153156Y347738I-3502J-1D01*
G03Y347590I186J-74D01*
G02X153402Y346300I-3256J-1289D01*
G02X146398I-3502J0D01*
G02X146644Y347590I3502J1D01*
G03Y347738I-186J74D01*
G37*
G36*
G01X19081Y364930D02*
G02X20500Y365230I1418J-3202D01*
G02X21919Y364930I1J-3502D01*
G03X22081I81J183D01*
G02X23500Y365230I1418J-3202D01*
G02X24919Y364930I1J-3502D01*
G03X25081I81J183D01*
G02X26500Y365230I1418J-3202D01*
G02X30002Y361728I0J-3502D01*
G02X29702Y360309I-3502J-1D01*
G03Y360147I183J-81D01*
G02X30002Y358728I-3202J-1418D01*
G02X26500Y355226I-3502J0D01*
G02X25081Y355526I-1J3502D01*
G03X24919I-81J-183D01*
G02X23500Y355226I-1418J3202D01*
G02X22081Y355526I-1J3502D01*
G03X21919I-81J-183D01*
G02X20500Y355226I-1418J3202D01*
G02X19081Y355526I-1J3502D01*
G03X18919I-81J-183D01*
G02X17500Y355226I-1418J3202D01*
G02X13998Y358728I0J3502D01*
G02X14298Y360147I3502J1D01*
G03Y360309I-183J81D01*
G02X13998Y361728I3202J1418D01*
G02X17500Y365230I3502J0D01*
G02X18919Y364930I1J-3502D01*
G03X19081I81J183D01*
G37*
G36*
G01X178439Y365492D02*
G02X179858Y365792I1418J-3202D01*
G02X181277Y365492I1J-3502D01*
G03X181439I81J183D01*
G02X182858Y365792I1418J-3202D01*
G02X184277Y365492I1J-3502D01*
G03X184439I81J183D01*
G02X185858Y365792I1418J-3202D01*
G02X189360Y362290I0J-3502D01*
G02X189155Y361108I-3502J-1D01*
G03Y360972I188J-68D01*
G02X189360Y359790I-3297J-1181D01*
G02X185858Y356288I-3502J0D01*
G02X184439Y356588I-1J3502D01*
G03X184277I-81J-183D01*
G02X182858Y356288I-1418J3202D01*
G02X181439Y356588I-1J3502D01*
G03X181277I-81J-183D01*
G02X179858Y356288I-1418J3202D01*
G02X178439Y356588I-1J3502D01*
G03X178277I-81J-183D01*
G02X176858Y356288I-1418J3202D01*
G02X173356Y359790I0J3502D01*
G02X173561Y360972I3502J1D01*
G03Y361108I-188J68D01*
G02X173356Y362290I3297J1181D01*
G02X176858Y365792I3502J0D01*
G02X178277Y365492I1J-3502D01*
G03X178439I81J183D01*
G37*
G36*
G01X49703Y366315D02*
G02X49498Y367497I3297J1181D01*
G02X49703Y368679I3502J1D01*
G03Y368815I-188J68D01*
G02X49498Y369997I3297J1181D01*
G02X56502I3502J0D01*
G02X56297Y368815I-3502J-1D01*
G03Y368679I188J-68D01*
G02X56502Y367497I-3297J-1181D01*
G02X56297Y366315I-3502J-1D01*
G03Y366179I188J-68D01*
G02X56502Y364997I-3297J-1181D01*
G02X49498I-3502J0D01*
G02X49703Y366179I3502J1D01*
G03Y366315I-188J68D01*
G37*
G36*
G01X146748Y366001D02*
G02X146398Y367528I3152J1526D01*
G02X146652Y368839I3502J2D01*
G03Y368989I-185J75D01*
G02X146398Y370300I3248J1309D01*
G02X153402I3502J0D01*
G02X153148Y368989I-3502J-2D01*
G03Y368839I185J-75D01*
G02X153402Y367528I-3248J-1309D01*
G02X153052Y366001I-3502J-1D01*
G03Y365827I180J-87D01*
G02X153402Y364300I-3152J-1526D01*
G02X146398I-3502J0D01*
G02X146748Y365827I3502J1D01*
G03Y366001I-180J87D01*
G37*
G36*
G01X114199Y399670D02*
G02X117500Y402002I3301J-1170D01*
G02X121002Y398500I0J-3502D01*
G02X119850Y395903I-3503J0D01*
G03X119796Y395822I134J-148D01*
G02X116500Y393500I-3296J1178D01*
G02X113000Y397000I0J3500D01*
G02X114145Y399589I3500J0D01*
G03X114199Y399670I-135J148D01*
G37*
G36*
G01X74107Y462168D02*
G02X76855Y458750I-752J-3418D01*
G02X73355Y455250I-3500J0D01*
G02X70665Y456510I-1J3500D01*
G03X70554Y456578I-154J-127D01*
G02X67798Y460000I746J3422D01*
G02X71300Y463502I3502J0D01*
G02X73996Y462236I1J-3502D01*
G03X74107Y462168I154J127D01*
G37*
G36*
G01X124483Y465642D02*
G02X126008Y465992I1526J-3150D01*
G02Y458992I0J-3500D01*
G02X123746Y459822I1J3500D01*
G03X123529Y459849I-129J-153D01*
G02X122000Y459498I-1528J3151D01*
G02Y466502I0J3502D01*
G02X124267Y465670I1J-3502D01*
G03X124483Y465642I130J152D01*
G37*
G36*
G01X80748Y773831D02*
G02X80968Y772610I-3280J-1221D01*
G02X73968I-3500J0D01*
G02X74124Y773643I3500J0D01*
G03X74120Y773772I-191J59D01*
G02X73898Y775000I3280J1227D01*
G02X80902I3502J0D01*
G02X80745Y773960I-3502J-3D01*
G03X80748Y773831I191J-60D01*
G37*
G36*
G01X136726Y778071D02*
G02X137675Y775675I-2550J-2396D01*
G02X134175Y772175I-3500J0D01*
G02X131390Y773555I0J3500D01*
G03X131375Y773573I-161J-119D01*
G02X130398Y776000I2526J2427D01*
G02X133900Y779502I3502J0D01*
G02X136712Y778088I0J-3503D01*
G03X136726Y778071I161J119D01*
G37*
G36*
G01X74148Y825761D02*
G02X73518Y827764I2869J2003D01*
G02X77018Y831264I3500J0D01*
G02X77662Y831204I-1J-3500D01*
G03X77823Y831244I37J197D01*
G02X80000Y832002I2176J-2744D01*
G02X83502Y828500I0J-3502D01*
G02X80650Y825058I-3503J0D01*
G01X80607Y825050D01*
X80538Y825002D01*
X80340Y824671D01*
X80330Y824588D01*
X80343Y824546D01*
G02X80502Y823500I-3343J-1043D01*
G02X73498I-3502J0D01*
G02X74146Y825531I3502J1D01*
G03X74148Y825761I-163J116D01*
G37*
G36*
G01X45106Y878996D02*
G02X44806Y880415I3202J1418D01*
G02X45106Y881834I3502J1D01*
G03Y881996I-183J81D01*
G02X44806Y883415I3202J1418D01*
G02X48308Y886918I3502J1D01*
G02X49490Y886712I-2J-3503D01*
G03X49626I68J188D01*
G02X50808Y886918I1184J-3297D01*
G02X54310Y883415I-1J-3503D01*
G02X54010Y881996I-3502J-1D01*
G03Y881834I183J-81D01*
G02X54310Y880415I-3202J-1418D01*
G02X54010Y878996I-3502J-1D01*
G03Y878834I183J-81D01*
G02X54310Y877415I-3202J-1418D01*
G02X50808Y873912I-3502J-1D01*
G02X49626Y874118I2J3503D01*
G03X49490I-68J-188D01*
G02X48308Y873912I-1184J3297D01*
G02X44806Y877415I1J3503D01*
G02X45106Y878834I3502J1D01*
G03Y878996I-183J81D01*
G37*
G36*
G01X146662Y891696D02*
G02X146362Y893115I3202J1418D01*
G02X146662Y894534I3502J1D01*
G03Y894696I-183J81D01*
G02X146362Y896115I3202J1418D01*
G02X149864Y899618I3502J1D01*
G02X151046Y899412I-2J-3503D01*
G03X151182I68J188D01*
G02X152364Y899618I1184J-3297D01*
G02X155866Y896115I-1J-3503D01*
G02X155566Y894696I-3502J-1D01*
G03Y894534I183J-81D01*
G02X155866Y893115I-3202J-1418D01*
G02X155566Y891696I-3502J-1D01*
G03Y891534I183J-81D01*
G02X155866Y890115I-3202J-1418D01*
G02X152364Y886612I-3502J-1D01*
G02X151182Y886818I2J3503D01*
G03X151046I-68J-188D01*
G02X149864Y886612I-1184J3297D01*
G02X146362Y890115I1J3503D01*
G02X146662Y891534I3502J1D01*
G03Y891696I-183J81D01*
G37*
G36*
G01X35727Y905660D02*
G02X36028Y904241I-3202J-1421D01*
G02X29022I-3503J0D01*
G02X29323Y905660I3503J-2D01*
G03Y905822I-183J81D01*
G02X29022Y907241I3202J1421D01*
G02X36028I3503J0D01*
G02X35727Y905822I-3503J2D01*
G03Y905660I183J-81D01*
G37*
G36*
G01X166079Y911919D02*
G02X166380Y910500I-3202J-1421D01*
G02X159374I-3503J0D01*
G02X159675Y911919I3503J-2D01*
G03Y912081I-183J81D01*
G02X159374Y913500I3202J1421D01*
G02X166380I3503J0D01*
G02X166079Y912081I-3503J2D01*
G03Y911919I183J-81D01*
G37*
G36*
G01X161328Y928359D02*
G02X159374Y931500I1549J3142D01*
G02X159675Y932919I3503J-2D01*
G03Y933081I-183J81D01*
G02X159374Y934500I3202J1421D01*
G02X166380I3503J0D01*
G02X166079Y933081I-3503J2D01*
G03Y932919I183J-81D01*
G02X166380Y931500I-3202J-1421D01*
G02X164426Y928359I-3503J1D01*
G03X164315Y928179I89J-179D01*
G01Y927821D01*
G03X164426Y927641I200J-1D01*
G02X166380Y924500I-1549J-3142D01*
G02X166079Y923081I-3503J2D01*
G03Y922919I183J-81D01*
G02X166380Y921500I-3202J-1421D01*
G02X159374I-3503J0D01*
G02X159675Y922919I3503J-2D01*
G03Y923081I-183J81D01*
G02X159374Y924500I3202J1421D01*
G02X161328Y927641I3503J-1D01*
G03X161439Y927821I-89J179D01*
G01Y928179D01*
G03X161328Y928359I-200J1D01*
G37*
G36*
G01X30789Y936234D02*
G02X31090Y934815I-3202J-1421D01*
G02X24084I-3503J0D01*
G02X24385Y936234I3503J-2D01*
G03Y936396I-183J81D01*
G02X24084Y937815I3202J1421D01*
G02X31090I3503J0D01*
G02X30789Y936396I-3503J2D01*
G03Y936234I183J-81D01*
G37*
G36*
G01X171379Y941519D02*
G02X171680Y940100I-3202J-1421D01*
G02X164674I-3503J0D01*
G02X164975Y941519I3503J-2D01*
G03Y941681I-183J81D01*
G02X164674Y943100I3202J1421D01*
G02X171680I3503J0D01*
G02X171379Y941681I-3503J2D01*
G03Y941519I183J-81D01*
G37*
G36*
G01X182227Y949768D02*
G02X180658Y949398I-1567J3133D01*
G02X177156Y952900I0J3502D01*
G02X177499Y954414I3503J2D01*
G03Y954586I-180J86D01*
G02X177156Y956100I3160J1512D01*
G02X180658Y959602I3502J0D01*
G02X182022Y959326I1J-3502D01*
G03X182189Y959332I77J184D01*
G02X183758Y959702I1567J-3133D01*
G02X185241Y959373I1J-3502D01*
G03X185397Y959368I84J181D01*
G02X186658Y959602I1259J-3268D01*
G02X190160Y956100I0J-3502D01*
G02X189817Y954586I-3503J-2D01*
G03Y954414I180J-86D01*
G02X190160Y952900I-3160J-1512D01*
G02X186658Y949398I-3502J0D01*
G02X185175Y949727I-1J3502D01*
G03X185019Y949732I-84J-181D01*
G02X183758Y949498I-1259J3268D01*
G02X182394Y949774I-1J3502D01*
G03X182227Y949768I-77J-184D01*
G37*
G36*
G01X166439Y965002D02*
G02X167858Y965302I1418J-3202D01*
G02Y958298I0J-3502D01*
G02X166439Y958598I-1J3502D01*
G03X166277I-81J-183D01*
G02X164858Y958298I-1418J3202D01*
G02Y965302I0J3502D01*
G02X166277Y965002I1J-3502D01*
G03X166439I81J183D01*
G37*
G36*
G01X134981Y960683D02*
G02X134776Y961865I3297J1181D01*
G02X138278Y965368I3502J1D01*
G02X139460Y965162I-2J-3503D01*
G03X139596I68J188D01*
G02X140778Y965368I1184J-3297D01*
G02X141998Y965148I-2J-3503D01*
G03X142138I70J188D01*
G02X143358Y965368I1222J-3283D01*
G02X146860Y961865I-1J-3503D01*
G02X146655Y960683I-3502J-1D01*
G03Y960547I188J-68D01*
G02X146860Y959365I-3297J-1181D01*
G02X143358Y955862I-3502J-1D01*
G02X142157Y956075I2J3503D01*
G03X142019I-69J-188D01*
G02X140818Y955862I-1203J3290D01*
G02X139617Y956075I2J3503D01*
G03X139479I-69J-188D01*
G02X138278Y955862I-1203J3290D01*
G02X134776Y959365I1J3503D01*
G02X134981Y960547I3502J1D01*
G03Y960683I-188J68D01*
G37*
G36*
G01X147785Y963832D02*
G02X147580Y965014I3297J1181D01*
G02X151082Y968516I3502J0D01*
G02X152264Y968311I1J-3502D01*
G03X152400I68J188D01*
G02X153582Y968516I1181J-3297D01*
G02X154802Y968297I1J-3502D01*
G03X154942I70J188D01*
G02X156162Y968516I1219J-3283D01*
G02X159664Y965014I0J-3502D01*
G02X159459Y963832I-3502J-1D01*
G03Y963696I188J-68D01*
G02X159664Y962514I-3297J-1181D01*
G02X156162Y959012I-3502J0D01*
G02X154961Y959224I-1J3502D01*
G03X154823I-69J-188D01*
G02X153622Y959012I-1200J3290D01*
G02X152421Y959224I-1J3502D01*
G03X152283I-69J-188D01*
G02X151082Y959012I-1200J3290D01*
G02X147580Y962514I0J3502D01*
G02X147785Y963696I3502J1D01*
G03Y963832I-188J68D01*
G37*
G36*
G01X185019Y965832D02*
G02X183758Y965598I-1259J3268D01*
G02X182394Y965874I-1J3502D01*
G03X182227Y965868I-77J-184D01*
G02X180658Y965498I-1567J3133D01*
G02Y972502I0J3502D01*
G02X182022Y972226I1J-3502D01*
G03X182189Y972232I77J184D01*
G02X183758Y972602I1567J-3133D01*
G02X185241Y972273I1J-3502D01*
G03X185397Y972268I84J181D01*
G02X186658Y972502I1259J-3268D01*
G02Y965498I0J-3502D01*
G02X185175Y965827I-1J3502D01*
G03X185019Y965832I-84J-181D01*
G37*
G36*
G01X39166Y1044502D02*
G02X40585Y1044802I1418J-3202D01*
G02Y1037798I0J-3502D01*
G02X39166Y1038098I-1J3502D01*
G03X39004I-81J-183D01*
G02X37585Y1037798I-1418J3202D01*
G02Y1044802I0J3502D01*
G02X39004Y1044502I1J-3502D01*
G03X39166I81J183D01*
G37*
G36*
G01X123980Y1040581D02*
G02X123680Y1042000I3202J1418D01*
G02X127182Y1045502I3502J0D01*
G02X128696Y1045159I2J-3503D01*
G03X128868I86J180D01*
G02X130382Y1045502I1512J-3160D01*
G02X131801Y1045202I1J-3502D01*
G03X131963I81J183D01*
G02X133382Y1045502I1418J-3202D01*
G02X136884Y1042000I0J-3502D01*
G02X136584Y1040581I-3502J-1D01*
G03Y1040419I183J-81D01*
G02X136884Y1039000I-3202J-1418D01*
G02X133382Y1035498I-3502J0D01*
G02X131963Y1035798I-1J3502D01*
G03X131801I-81J-183D01*
G02X130382Y1035498I-1418J3202D01*
G02X128868Y1035841I-2J3503D01*
G03X128696I-86J-180D01*
G02X127182Y1035498I-1512J3160D01*
G02X123680Y1039000I0J3502D01*
G02X123980Y1040419I3502J1D01*
G03Y1040581I-183J81D01*
G37*
G36*
G01X148063Y1046202D02*
G02X149482Y1046502I1418J-3202D01*
G02Y1039498I0J-3502D01*
G02X148063Y1039798I-1J3502D01*
G03X147901I-81J-183D01*
G02X146482Y1039498I-1418J3202D01*
G02Y1046502I0J3502D01*
G02X147901Y1046202I1J-3502D01*
G03X148063I81J183D01*
G37*
G36*
G01X10209Y1048036D02*
G02X9990Y1049256I3283J1219D01*
G02X10195Y1050438I3502J1D01*
G03Y1050574I-188J68D01*
G02X9990Y1051756I3297J1181D01*
G02X16994I3502J0D01*
G02X16789Y1050574I-3502J-1D01*
G03Y1050438I188J-68D01*
G02X16994Y1049256I-3297J-1181D01*
G02X16775Y1048036I-3502J-1D01*
G03Y1047896I188J-70D01*
G02X16994Y1046676I-3283J-1219D01*
G02X16882Y1045794I-3502J-3D01*
G01X16868Y1045742D01*
X16895Y1045642D01*
X17210Y1045321D01*
X17311Y1045292D01*
X17363Y1045305D01*
G02X18185Y1045402I819J-3405D01*
G02X19699Y1045059I2J-3503D01*
G03X19871I86J180D01*
G02X21385Y1045402I1512J-3160D01*
G02X23041Y1044986I0J-3502D01*
G03X23219Y1044981I94J177D01*
G02X24685Y1045302I1465J-3181D01*
G02X28188Y1041800I1J-3502D01*
G02X27887Y1040381I-3503J2D01*
G03Y1040219I183J-81D01*
G02X28188Y1038800I-3202J-1421D01*
G02X24685Y1035298I-3503J1D01*
G02X23029Y1035714I0J3502D01*
G03X22851Y1035719I-94J-177D01*
G02X21385Y1035398I-1465J3181D01*
G02X19871Y1035741I-2J3503D01*
G03X19699I-86J-180D01*
G02X18185Y1035398I-1512J3160D01*
G02X14682Y1038900I-1J3502D01*
G02X14983Y1040319I3503J-2D01*
G03Y1040481I-183J81D01*
G02X14682Y1041900I3202J1421D01*
G02X14795Y1042782I3503J-1D01*
G01X14809Y1042834D01*
X14782Y1042934D01*
X14467Y1043255D01*
X14366Y1043284D01*
X14314Y1043271D01*
G02X13492Y1043174I-819J3405D01*
G02X9990Y1046676I0J3502D01*
G02X10209Y1047896I3502J1D01*
G03Y1048036I-188J70D01*
G37*
G36*
G01X128696Y1051841D02*
G02X127182Y1051498I-1512J3160D01*
G02Y1058502I0J3502D01*
G02X128696Y1058159I2J-3503D01*
G03X128868I86J180D01*
G02X130382Y1058502I1512J-3160D01*
G02X131801Y1058202I1J-3502D01*
G03X131963I81J183D01*
G02X133382Y1058502I1418J-3202D01*
G02Y1051498I0J-3502D01*
G02X131963Y1051798I-1J3502D01*
G03X131801I-81J-183D01*
G02X130382Y1051498I-1418J3202D01*
G02X128868Y1051841I-2J3503D01*
G03X128696I-86J-180D01*
G37*
G36*
G01X139775Y1074318D02*
G02X139570Y1075500I3297J1181D01*
G02X139775Y1076682I3502J1D01*
G03Y1076818I-188J68D01*
G02X139570Y1078000I3297J1181D01*
G02X146574I3502J0D01*
G02X146369Y1076818I-3502J-1D01*
G03Y1076682I188J-68D01*
G02X146574Y1075500I-3297J-1181D01*
G02X146369Y1074318I-3502J-1D01*
G03Y1074182I188J-68D01*
G02X146574Y1073000I-3297J-1181D01*
G02X145136Y1070170I-3502J-1D01*
G03X145055Y1070030I118J-162D01*
G02X144869Y1069218I-3483J370D01*
G03Y1069082I188J-68D01*
G02X145074Y1067900I-3297J-1181D01*
G02X138070I-3502J0D01*
G02X138275Y1069082I3502J1D01*
G03Y1069218I-188J68D01*
G02X138070Y1070400I3297J1181D01*
G02X139508Y1073230I3502J1D01*
G03X139589Y1073370I-118J162D01*
G02X139775Y1074182I3483J-370D01*
G03Y1074318I-188J68D01*
G37*
G36*
G01X52758Y1073977D02*
G02X52198Y1075878I2942J1900D01*
G02X52591Y1077491I3502J1D01*
G03Y1077676I-177J92D01*
G02X52198Y1079289I3109J1612D01*
G02X59202I3502J0D01*
G02X58809Y1077676I-3502J-1D01*
G03Y1077491I177J-93D01*
G02X59202Y1075878I-3109J-1612D01*
G02X58643Y1073978I-3503J-2D01*
G03Y1073761I168J-109D01*
G02X59204Y1071860I-2942J-1901D01*
G02X58810Y1070247I-3503J1D01*
G03Y1070062I177J-93D01*
G02X59204Y1068449I-3109J-1614D01*
G02X59149Y1067832I-3503J1D01*
G01X59139Y1067777D01*
X59177Y1067676D01*
X59536Y1067386D01*
X59643Y1067370D01*
X59695Y1067391D01*
G02X61029Y1067656I1336J-3238D01*
G02X64532Y1064153I0J-3503D01*
G02X64138Y1062540I-3503J1D01*
G03Y1062355I177J-92D01*
G02X64532Y1060742I-3109J-1614D01*
G02X57526I-3503J0D01*
G02X57920Y1062355I3503J-1D01*
G03Y1062540I-177J93D01*
G02X57526Y1064153I3109J1614D01*
G02X57581Y1064770I3503J-1D01*
G01X57591Y1064825D01*
X57553Y1064926D01*
X57194Y1065216D01*
X57087Y1065232D01*
X57035Y1065211D01*
G02X55701Y1064946I-1336J3238D01*
G02X52198Y1068449I0J3503D01*
G02X52592Y1070062I3503J-1D01*
G03Y1070247I-177J92D01*
G02X52198Y1071860I3109J1614D01*
G02X52758Y1073760I3503J0D01*
G03Y1073977I-168J108D01*
G37*
G36*
G01X58744Y1092278D02*
G02X59138Y1090665I-3109J-1614D01*
G02X52132I-3503J0D01*
G02X52526Y1092278I3503J-1D01*
G03Y1092463I-177J92D01*
G02X52132Y1094076I3109J1614D01*
G02X59138I3503J0D01*
G02X58744Y1092463I-3503J1D01*
G03Y1092278I177J-92D01*
G37*
G36*
G01X139775Y1093818D02*
G02X139570Y1095000I3297J1181D01*
G02X139775Y1096182I3502J1D01*
G03Y1096318I-188J68D01*
G02X139570Y1097500I3297J1181D01*
G02X146574I3502J0D01*
G02X146369Y1096318I-3502J-1D01*
G03Y1096182I188J-68D01*
G02X146574Y1095000I-3297J-1181D01*
G02X146369Y1093818I-3502J-1D01*
G03Y1093682I188J-68D01*
G02X146574Y1092500I-3297J-1181D01*
G02X139570I-3502J0D01*
G02X139775Y1093682I3502J1D01*
G03Y1093818I-188J68D01*
G37*
G36*
G01X177256Y1105243D02*
G02X176956Y1106662I3202J1418D01*
G02X180458Y1110164I3502J0D01*
G02X181877Y1109864I1J-3502D01*
G03X182039I81J183D01*
G02X183458Y1110164I1418J-3202D01*
G02X184877Y1109864I1J-3502D01*
G03X185039I81J183D01*
G02X186458Y1110164I1418J-3202D01*
G02X189960Y1106662I0J-3502D01*
G02X189660Y1105243I-3502J-1D01*
G03Y1105081I183J-81D01*
G02X189960Y1103662I-3202J-1418D01*
G02X186458Y1100160I-3502J0D01*
G02X185039Y1100460I-1J3502D01*
G03X184877I-81J-183D01*
G02X183458Y1100160I-1418J3202D01*
G02X182039Y1100460I-1J3502D01*
G03X181877I-81J-183D01*
G02X180458Y1100160I-1418J3202D01*
G02X176956Y1103662I0J3502D01*
G02X177256Y1105081I3502J1D01*
G03Y1105243I-183J81D01*
G37*
G36*
G01X15798Y1105881D02*
G02X15498Y1107300I3202J1418D01*
G02X19000Y1110802I3502J0D01*
G02X20419Y1110502I1J-3502D01*
G03X20581I81J183D01*
G02X22000Y1110802I1418J-3202D01*
G02X23419Y1110502I1J-3502D01*
G03X23581I81J183D01*
G02X25000Y1110802I1418J-3202D01*
G02X28502Y1107300I0J-3502D01*
G02X28202Y1105881I-3502J-1D01*
G03Y1105719I183J-81D01*
G02X28502Y1104300I-3202J-1418D01*
G02X25000Y1100798I-3502J0D01*
G02X23581Y1101098I-1J3502D01*
G03X23419I-81J-183D01*
G02X22000Y1100798I-1418J3202D01*
G02X20581Y1101098I-1J3502D01*
G03X20419I-81J-183D01*
G02X19000Y1100798I-1418J3202D01*
G02X15498Y1104300I0J3502D01*
G02X15798Y1105719I3502J1D01*
G03Y1105881I-183J81D01*
G37*
G36*
G01X78002Y1137166D02*
G02X79500Y1137502I1497J-3166D01*
G02X83002Y1134000I0J-3502D01*
G02X79639Y1130500I-3503J0D01*
G03X79562Y1130481I8J-200D01*
G02X78075Y1130150I-1486J3169D01*
G02X74575Y1133650I0J3500D01*
G02X77925Y1137147I3500J0D01*
G03X78002Y1137166I-8J200D01*
G37*
G36*
G01X124559Y1140913D02*
G02X126500Y1141500I1940J-2913D01*
G02Y1134500I0J-3500D01*
G02X125609Y1134615I-1J3500D01*
G03X125447Y1134588I-51J-193D01*
G02X123500Y1133998I-1945J2912D01*
G02Y1141002I0J3502D01*
G02X124397Y1140886I3J-3502D01*
G03X124559Y1140913I51J193D01*
G37*
G36*
G01X124544Y1184158D02*
G02X127760Y1180670I-284J-3488D01*
G02X124260Y1177170I-3500J0D01*
G02X122797Y1177490I-1J3500D01*
G03X122729Y1177508I-84J-181D01*
G02X119498Y1181000I272J3492D01*
G02X123000Y1184502I3502J0D01*
G02X124476Y1184176I0J-3502D01*
G03X124544Y1184158I84J182D01*
G37*
G36*
G01X72934Y1188604D02*
G02X76400Y1191602I3466J-505D01*
G02X79902Y1188100I0J-3502D01*
G02X78177Y1185082I-3503J0D01*
G03X78081Y1184939I102J-172D01*
G02X74618Y1181947I-3463J508D01*
G02X71118Y1185447I0J3500D01*
G02X72838Y1188460I3499J0D01*
G03X72934Y1188604I-102J172D01*
G37*
G36*
G01X165362Y216124D02*
G02X165062Y217543I3202J1418D01*
G02X172066I3502J0D01*
G02X171766Y216124I-3502J-1D01*
G03Y215962I183J-81D01*
G02X172066Y214543I-3202J-1418D01*
G02X168564Y211040I-3502J-1D01*
G02X168118Y211069I4J3503D01*
G01X168058Y211077D01*
X167953Y211026D01*
X167701Y210610D01*
X167704Y210493D01*
X167739Y210444D01*
G02X168366Y208443I-2875J-2000D01*
G02X168066Y207024I-3502J-1D01*
G03Y206862I183J-81D01*
G02X168366Y205443I-3202J-1418D01*
G02X167201Y202834I-3502J-1D01*
G01X167168Y202805D01*
X167134Y202726D01*
X167140Y202335D01*
X167177Y202258D01*
X167211Y202230D01*
G02X168466Y199543I-2247J-2686D01*
G02X168166Y198124I-3502J-1D01*
G03Y197962I183J-81D01*
G02X168466Y196543I-3202J-1418D01*
G02X166163Y193252I-3503J0D01*
G01X166102Y193230D01*
X166030Y193124D01*
X166044Y192615D01*
X166122Y192513D01*
X166184Y192494D01*
G02X168666Y189143I-1021J-3351D01*
G02X168366Y187724I-3502J-1D01*
G03Y187562I183J-81D01*
G02X168666Y186143I-3202J-1418D01*
G02X161662I-3502J0D01*
G02X161962Y187562I3502J1D01*
G03Y187724I-183J81D01*
G02X161662Y189143I3202J1418D01*
G02X163965Y192434I3503J0D01*
G01X164026Y192456D01*
X164098Y192562D01*
X164084Y193071D01*
X164006Y193173D01*
X163944Y193192D01*
G02X161462Y196543I1021J3351D01*
G02X161762Y197962I3502J1D01*
G03Y198124I-183J81D01*
G02X161462Y199543I3202J1418D01*
G02X162627Y202152I3502J1D01*
G01X162660Y202181D01*
X162694Y202260D01*
X162688Y202651D01*
X162651Y202728D01*
X162617Y202756D01*
G02X161362Y205443I2247J2686D01*
G02X161662Y206862I3502J1D01*
G03Y207024I-183J81D01*
G02X161362Y208443I3202J1418D01*
G02X164864Y211946I3502J1D01*
G02X165310Y211917I-4J-3503D01*
G01X165370Y211909D01*
X165475Y211960D01*
X165727Y212376D01*
X165724Y212493D01*
X165689Y212542D01*
G02X165062Y214543I2875J2000D01*
G02X165362Y215962I3502J1D01*
G03Y216124I-183J81D01*
G37*
G36*
G01X28109Y238390D02*
G02X29291Y238596I1184J-3297D01*
G02X30511Y238376I-2J-3503D01*
G03X30651I70J188D01*
G02X31871Y238596I1222J-3283D01*
G02X35374Y235093I0J-3503D01*
G02X35168Y233911I-3503J2D01*
G03Y233775I188J-68D01*
G02X35374Y232593I-3297J-1184D01*
G02X31871Y229090I-3503J0D01*
G02X30670Y229303I2J3503D01*
G03X30532I-69J-188D01*
G02X29331Y229090I-1203J3290D01*
G02X28130Y229303I2J3503D01*
G03X27992I-69J-188D01*
G02X26791Y229090I-1203J3290D01*
G02X23721Y230907I0J3502D01*
G01X23692Y230959D01*
X23587Y231015D01*
X23103Y230971D01*
X23010Y230897D01*
X22991Y230840D01*
G02X22964Y230762I-3323J1107D01*
G03Y230626I188J-68D01*
G02X23170Y229444I-3297J-1184D01*
G02X19667Y225942I-3503J1D01*
G02X18466Y226154I-1J3502D01*
G03X18328I-69J-188D01*
G02X17127Y225942I-1200J3290D01*
G02X15926Y226154I-1J3502D01*
G03X15788I-69J-188D01*
G02X14587Y225942I-1200J3290D01*
G02X11084Y229444I-1J3502D01*
G02X11290Y230626I3503J-2D01*
G03Y230762I-188J68D01*
G02X11084Y231944I3297J1184D01*
G02X14587Y235446I3503J-1D01*
G02X15769Y235241I1J-3502D01*
G03X15905I68J188D01*
G02X17087Y235446I1181J-3297D01*
G02X18307Y235227I1J-3502D01*
G03X18447I70J188D01*
G02X19667Y235446I1219J-3283D01*
G02X22737Y233630I0J-3503D01*
G01X22766Y233578D01*
X22871Y233522D01*
X23355Y233566D01*
X23448Y233640D01*
X23467Y233697D01*
G02X23494Y233775I3323J-1107D01*
G03Y233911I-188J68D01*
G02X23288Y235093I3297J1184D01*
G02X26791Y238596I3503J0D01*
G02X27973Y238390I-2J-3503D01*
G03X28109I68J188D01*
G37*
G36*
G01X151800D02*
G02X152982Y238596I1184J-3297D01*
G02X154202Y238376I-2J-3503D01*
G03X154342I70J188D01*
G02X155562Y238596I1222J-3283D01*
G02X159064Y235093I-1J-3503D01*
G02X158859Y233911I-3502J-1D01*
G03Y233775I188J-68D01*
G02X159064Y232593I-3297J-1181D01*
G02X155562Y229090I-3502J-1D01*
G02X154361Y229303I2J3503D01*
G03X154223I-69J-188D01*
G02X153022Y229090I-1203J3290D01*
G02X151821Y229303I2J3503D01*
G03X151683I-69J-188D01*
G02X150482Y229090I-1203J3290D01*
G02X147412Y230907I0J3502D01*
G01X147383Y230959D01*
X147278Y231015D01*
X146794Y230971D01*
X146701Y230897D01*
X146682Y230840D01*
G02X146655Y230762I-3323J1107D01*
G03Y230626I188J-68D01*
G02X146860Y229444I-3297J-1181D01*
G02X143358Y225942I-3502J0D01*
G02X142157Y226154I-1J3502D01*
G03X142019I-69J-188D01*
G02X140818Y225942I-1200J3290D01*
G02X139598Y226161I-1J3502D01*
G03X139458I-70J-188D01*
G02X138238Y225942I-1219J3283D01*
G02X134736Y229444I0J3502D01*
G02X134923Y230574I3502J1D01*
G03X134921Y230709I-189J65D01*
G02X134696Y231944I3277J1235D01*
G02X138198Y235446I3502J0D01*
G02X139418Y235227I1J-3502D01*
G03X139558I70J188D01*
G02X140778Y235446I1219J-3283D01*
G02X141998Y235227I1J-3502D01*
G03X142138I70J188D01*
G02X143358Y235446I1219J-3283D01*
G02X146428Y233630I0J-3503D01*
G01X146457Y233578D01*
X146562Y233522D01*
X147046Y233566D01*
X147139Y233640D01*
X147158Y233697D01*
G02X147185Y233775I3323J-1107D01*
G03Y233911I-188J68D01*
G02X146980Y235093I3297J1181D01*
G02X150482Y238596I3502J1D01*
G02X151664Y238390I-2J-3503D01*
G03X151800I68J188D01*
G37*
G36*
G01X61024Y320302D02*
G02X62225Y320514I1200J-3290D01*
G02X63426Y320302I1J-3502D01*
G03X63564I69J188D01*
G02X64765Y320514I1200J-3290D01*
G02X68268Y317012I1J-3502D01*
G02X68062Y315830I-3503J2D01*
G03Y315694I188J-68D01*
G02X68268Y314512I-3297J-1184D01*
G02X64765Y311010I-3503J1D01*
G02X63583Y311215I-1J3502D01*
G03X63447I-68J-188D01*
G02X62265Y311010I-1181J3297D01*
G02X61045Y311229I-1J3502D01*
G03X60905I-70J-188D01*
G02X59685Y311010I-1219J3283D01*
G02X56615Y312826I0J3503D01*
G01X56586Y312878D01*
X56481Y312934D01*
X55997Y312890D01*
X55904Y312816D01*
X55885Y312759D01*
G02X55858Y312681I-3323J1107D01*
G03Y312545I188J-68D01*
G02X56064Y311363I-3297J-1184D01*
G02X52561Y307860I-3503J0D01*
G02X51379Y308066I2J3503D01*
G03X51243I-68J-188D01*
G02X50061Y307860I-1184J3297D01*
G02X48841Y308080I2J3503D01*
G03X48701I-70J-188D01*
G02X47481Y307860I-1222J3283D01*
G02X43978Y311363I0J3503D01*
G02X44184Y312545I3503J-2D01*
G03Y312681I-188J68D01*
G02X43978Y313863I3297J1184D01*
G02X47481Y317366I3503J0D01*
G02X48682Y317153I-2J-3503D01*
G03X48820I69J188D01*
G02X50021Y317366I1203J-3290D01*
G02X51222Y317153I-2J-3503D01*
G03X51360I69J188D01*
G02X52561Y317366I1203J-3290D01*
G02X55631Y315549I0J-3502D01*
G01X55660Y315497D01*
X55765Y315441D01*
X56249Y315485D01*
X56342Y315559D01*
X56361Y315616D01*
G02X56388Y315694I3323J-1107D01*
G03Y315830I-188J68D01*
G02X56182Y317012I3297J1184D01*
G02X59685Y320514I3503J-1D01*
G02X60886Y320302I1J-3502D01*
G03X61024I69J188D01*
G37*
G36*
G01X170321D02*
G02X171522Y320514I1200J-3290D01*
G02X172723Y320302I1J-3502D01*
G03X172861I69J188D01*
G02X174062Y320514I1200J-3290D01*
G02X177564Y317012I0J-3502D01*
G02X177359Y315830I-3502J-1D01*
G03Y315694I188J-68D01*
G02X177564Y314512I-3297J-1181D01*
G02X174062Y311010I-3502J0D01*
G02X172880Y311215I-1J3502D01*
G03X172744I-68J-188D01*
G02X171562Y311010I-1181J3297D01*
G02X170342Y311229I-1J3502D01*
G03X170202I-70J-188D01*
G02X168982Y311010I-1219J3283D01*
G02X165912Y312826I0J3503D01*
G01X165883Y312878D01*
X165778Y312934D01*
X165294Y312890D01*
X165201Y312816D01*
X165182Y312759D01*
G02X165155Y312681I-3323J1107D01*
G03Y312545I188J-68D01*
G02X165360Y311363I-3297J-1181D01*
G02X161858Y307860I-3502J-1D01*
G02X160676Y308066I2J3503D01*
G03X160540I-68J-188D01*
G02X159358Y307860I-1184J3297D01*
G02X158138Y308080I2J3503D01*
G03X157998I-70J-188D01*
G02X156778Y307860I-1222J3283D01*
G02X153276Y311363I1J3503D01*
G02X153481Y312545I3502J1D01*
G03Y312681I-188J68D01*
G02X153276Y313863I3297J1181D01*
G02X156778Y317366I3502J1D01*
G02X157979Y317153I-2J-3503D01*
G03X158117I69J188D01*
G02X159318Y317366I1203J-3290D01*
G02X160519Y317153I-2J-3503D01*
G03X160657I69J188D01*
G02X161858Y317366I1203J-3290D01*
G02X164928Y315549I0J-3502D01*
G01X164957Y315497D01*
X165062Y315441D01*
X165546Y315485D01*
X165639Y315559D01*
X165658Y315616D01*
G02X165685Y315694I3323J-1107D01*
G03Y315830I-188J68D01*
G02X165480Y317012I3297J1181D01*
G02X168982Y320514I3502J0D01*
G02X170183Y320302I1J-3502D01*
G03X170321I69J188D01*
G37*
G36*
G01X29423Y926822D02*
G02X29122Y928241I3202J1421D01*
G02X36128I3503J0D01*
G02X35827Y926822I-3503J2D01*
G03Y926660I183J-81D01*
G02X36128Y925241I-3202J-1421D01*
G02X33824Y921950I-3502J0D01*
G01X33763Y921928D01*
X33691Y921822D01*
X33705Y921313D01*
X33783Y921211D01*
X33845Y921192D01*
G02X36328Y917841I-1020J-3351D01*
G02X36027Y916422I-3503J2D01*
G03Y916260I183J-81D01*
G02X36328Y914841I-3202J-1421D01*
G02X29322I-3503J0D01*
G02X29623Y916260I3503J-2D01*
G03Y916422I-183J81D01*
G02X29322Y917841I3202J1421D01*
G02X31626Y921132I3502J0D01*
G01X31687Y921154D01*
X31759Y921260D01*
X31745Y921769D01*
X31667Y921871D01*
X31605Y921890D01*
G02X29122Y925241I1020J3351D01*
G02X29423Y926660I3503J-2D01*
G03Y926822I-183J81D01*
G37*
G36*
G01X45434Y973625D02*
G02X45228Y974807I3297J1184D01*
G02X52234I3503J0D01*
G02X52028Y973625I-3503J2D01*
G03Y973489I188J-68D01*
G02X52234Y972307I-3297J-1184D01*
G02X51960Y970951I-3503J2D01*
G03X51955Y970811I185J-77D01*
G02X52134Y969707I-3324J-1105D01*
G02X51928Y968525I-3503J2D01*
G03Y968389I188J-68D01*
G02X52134Y967207I-3297J-1184D01*
G02X51911Y965977I-3504J0D01*
G03Y965837I187J-70D01*
G02X52134Y964607I-3281J-1230D01*
G02X51928Y963425I-3503J2D01*
G03Y963289I188J-68D01*
G02X52134Y962107I-3297J-1184D01*
G02X51955Y961003I-3503J1D01*
G03X51960Y960863I190J-63D01*
G02X52234Y959507I-3229J-1358D01*
G02X52028Y958325I-3503J2D01*
G03Y958189I188J-68D01*
G02X52234Y957007I-3297J-1184D01*
G02X48731Y953504I-3503J0D01*
G02X45414Y955882I0J3502D01*
G01X45397Y955933D01*
X45319Y956002D01*
X44877Y956096D01*
X44778Y956065D01*
X44741Y956025D01*
G02X42167Y954898I-2574J2376D01*
G02X40748Y955198I-1J3502D01*
G03X40586I-81J-183D01*
G02X39167Y954898I-1418J3202D01*
G02X35740Y957677I0J3503D01*
G01X35727Y957740D01*
X35634Y957825D01*
X35133Y957892D01*
X35021Y957833D01*
X34992Y957776D01*
G02X31871Y955862I-3122J1589D01*
G02X30670Y956075I2J3503D01*
G03X30532I-69J-188D01*
G02X29331Y955862I-1203J3290D01*
G02X28130Y956075I2J3503D01*
G03X27992I-69J-188D01*
G02X26791Y955862I-1203J3290D01*
G02X23721Y957679I0J3502D01*
G01X23692Y957731D01*
X23587Y957787D01*
X23103Y957743D01*
X23010Y957669D01*
X22991Y957612D01*
G02X22964Y957534I-3323J1107D01*
G03Y957398I188J-68D01*
G02X23170Y956216I-3297J-1184D01*
G02X19667Y952714I-3503J1D01*
G02X18466Y952926I-1J3502D01*
G03X18328I-69J-188D01*
G02X17127Y952714I-1200J3290D01*
G02X15926Y952926I-1J3502D01*
G03X15788I-69J-188D01*
G02X14587Y952714I-1200J3290D01*
G02X11084Y956216I-1J3502D01*
G02X11290Y957398I3503J-2D01*
G03Y957534I-188J68D01*
G02X11084Y958716I3297J1184D01*
G02X14587Y962218I3503J-1D01*
G02X15769Y962013I1J-3502D01*
G03X15905I68J188D01*
G02X17087Y962218I1181J-3297D01*
G02X18307Y961999I1J-3502D01*
G03X18447I70J188D01*
G02X19667Y962218I1219J-3283D01*
G02X22737Y960402I0J-3503D01*
G01X22766Y960350D01*
X22871Y960294D01*
X23355Y960338D01*
X23448Y960412D01*
X23467Y960469D01*
G02X23494Y960547I3323J-1107D01*
G03Y960683I-188J68D01*
G02X23288Y961865I3297J1184D01*
G02X26791Y965368I3503J0D01*
G02X27973Y965162I-2J-3503D01*
G03X28109I68J188D01*
G02X29291Y965368I1184J-3297D01*
G02X30511Y965148I-2J-3503D01*
G03X30651I70J188D01*
G02X31871Y965368I1222J-3283D01*
G02X35374Y961865I0J-3503D01*
G02X35168Y960683I-3503J2D01*
G03Y960547I188J-68D01*
G02X35298Y960088I-3297J-1182D01*
G01X35311Y960025D01*
X35404Y959940D01*
X35905Y959873D01*
X36017Y959932D01*
X36046Y959989D01*
G02X39167Y961902I3121J-1589D01*
G02X40586Y961602I1J-3502D01*
G03X40748I81J183D01*
G02X42167Y961902I1418J-3202D01*
G02X44946Y960532I1J-3502D01*
G03X45138Y960457I158J122D01*
G01X45250Y960476D01*
G03X45407Y960610I-33J197D01*
G01Y960611D01*
G03X45402Y960751I-190J63D01*
G02X45128Y962107I3229J1358D01*
G02X45334Y963289I3503J-2D01*
G03Y963425I-188J68D01*
G02X45128Y964607I3297J1184D01*
G02X45351Y965837I3504J0D01*
G03Y965977I-187J70D01*
G02X45128Y967207I3281J1230D01*
G02X45334Y968389I3503J-2D01*
G03Y968525I-188J68D01*
G02X45128Y969707I3297J1184D01*
G02X45402Y971063I3503J-2D01*
G03X45407Y971203I-185J77D01*
G02X45228Y972307I3324J1105D01*
G02X45434Y973489I3503J-2D01*
G03Y973625I-188J68D01*
G37*
G36*
G01X61524Y1047074D02*
G02X62725Y1047286I1200J-3290D01*
G02X63926Y1047074I1J-3502D01*
G03X64064I69J188D01*
G02X65265Y1047286I1200J-3290D01*
G02X68768Y1043784I1J-3502D01*
G02X68562Y1042602I-3503J2D01*
G03Y1042466I188J-68D01*
G02X68768Y1041284I-3297J-1184D01*
G02X65265Y1037782I-3503J1D01*
G02X64083Y1037987I-1J3502D01*
G03X63947I-68J-188D01*
G02X62765Y1037782I-1181J3297D01*
G02X61545Y1038001I-1J3502D01*
G03X61405I-70J-188D01*
G02X60185Y1037782I-1219J3283D01*
G02X57115Y1039598I0J3503D01*
G01X57086Y1039650D01*
X56981Y1039706D01*
X56497Y1039662D01*
X56404Y1039588D01*
X56385Y1039531D01*
G02X56358Y1039453I-3323J1107D01*
G03Y1039317I188J-68D01*
G02X56564Y1038135I-3297J-1184D01*
G02X53061Y1034632I-3503J0D01*
G02X51879Y1034838I2J3503D01*
G03X51743I-68J-188D01*
G02X50561Y1034632I-1184J3297D01*
G02X49341Y1034852I2J3503D01*
G03X49201I-70J-188D01*
G02X47981Y1034632I-1222J3283D01*
G02X44478Y1038135I0J3503D01*
G02X44684Y1039317I3503J-2D01*
G03Y1039453I-188J68D01*
G02X44478Y1040635I3297J1184D01*
G02X47981Y1044138I3503J0D01*
G02X49182Y1043925I-2J-3503D01*
G03X49320I69J188D01*
G02X50521Y1044138I1203J-3290D01*
G02X51722Y1043925I-2J-3503D01*
G03X51860I69J188D01*
G02X53061Y1044138I1203J-3290D01*
G02X56131Y1042321I0J-3502D01*
G01X56160Y1042269D01*
X56265Y1042213D01*
X56749Y1042257D01*
X56842Y1042331D01*
X56861Y1042388D01*
G02X56888Y1042466I3323J-1107D01*
G03Y1042602I-188J68D01*
G02X56682Y1043784I3297J1184D01*
G02X60185Y1047286I3503J-1D01*
G02X61386Y1047074I1J-3502D01*
G03X61524I69J188D01*
G37*
G36*
G01X170321D02*
G02X171522Y1047286I1200J-3290D01*
G02X172723Y1047074I1J-3502D01*
G03X172861I69J188D01*
G02X174062Y1047286I1200J-3290D01*
G02X177564Y1043784I0J-3502D01*
G02X177359Y1042602I-3502J-1D01*
G03Y1042466I188J-68D01*
G02X177564Y1041284I-3297J-1181D01*
G02X174062Y1037782I-3502J0D01*
G02X172880Y1037987I-1J3502D01*
G03X172744I-68J-188D01*
G02X171562Y1037782I-1181J3297D01*
G02X170342Y1038001I-1J3502D01*
G03X170202I-70J-188D01*
G02X168982Y1037782I-1219J3283D01*
G02X165912Y1039598I0J3503D01*
G01X165883Y1039650D01*
X165778Y1039706D01*
X165294Y1039662D01*
X165201Y1039588D01*
X165182Y1039531D01*
G02X165155Y1039453I-3323J1107D01*
G03Y1039317I188J-68D01*
G02X165360Y1038135I-3297J-1181D01*
G02X161858Y1034632I-3502J-1D01*
G02X160676Y1034838I2J3503D01*
G03X160540I-68J-188D01*
G02X159358Y1034632I-1184J3297D01*
G02X158138Y1034852I2J3503D01*
G03X157998I-70J-188D01*
G02X156778Y1034632I-1222J3283D01*
G02X153276Y1038135I1J3503D01*
G02X153481Y1039317I3502J1D01*
G03Y1039453I-188J68D01*
G02X153276Y1040635I3297J1181D01*
G02X156778Y1044138I3502J1D01*
G02X157979Y1043925I-2J-3503D01*
G03X158117I69J188D01*
G02X159318Y1044138I1203J-3290D01*
G02X160519Y1043925I-2J-3503D01*
G03X160657I69J188D01*
G02X161858Y1044138I1203J-3290D01*
G02X164928Y1042321I0J-3502D01*
G01X164957Y1042269D01*
X165062Y1042213D01*
X165546Y1042257D01*
X165639Y1042331D01*
X165658Y1042388D01*
G02X165685Y1042466I3323J-1107D01*
G03Y1042602I-188J68D01*
G02X165480Y1043784I3297J1181D01*
G02X168982Y1047286I3502J0D01*
G02X170183Y1047074I1J-3502D01*
G03X170321I69J188D01*
G37*
G54D37*
X77518Y406378D03*
X67500Y124242D03*
G54D36*
X7500Y44000D03*
X23000Y760000D03*
X13500Y862500D03*
X76000Y133500D03*
X71000Y427000D03*
X70500Y443500D03*
X60000Y797925D03*
X68000Y804606D03*
X75500Y852500D03*
X82500Y398000D03*
X82000Y415000D03*
X84000Y844950D03*
X102500Y979500D03*
X123500Y59500D03*
X107000Y389500D03*
X123000Y829114D03*
X135750Y132750D03*
X127500Y129500D03*
X165500Y1229900D03*
G54D34*
X173228Y474842D03*
X30315Y768150D03*
Y41378D03*
X173228Y1201614D03*
Y111456D03*
X30315Y1131536D03*
X173228Y838228D03*
X30315Y404764D03*
G54D35*
X34252Y80354D03*
X26378Y88228D03*
X34252Y443740D03*
X26378Y451614D03*
X34252Y807126D03*
X26378Y815000D03*
X34252Y1170512D03*
X26378Y1178386D03*
X169291Y72480D03*
Y435866D03*
Y799252D03*
Y1162638D03*
X177165Y64606D03*
Y427992D03*
Y791378D03*
Y1154764D03*
G54D33*
X-58189Y619685D03*
Y1307087D03*
X44000Y17500D03*
X178500D03*
X20000Y1307000D03*
G54D26*
X42717Y595122D03*
X101772Y178779D03*
Y926810D03*
X160827Y595122D03*
G54D17*
X7500Y44000D03*
X9400Y241516D03*
X10500Y274500D03*
X11800Y284000D03*
X12000Y641000D03*
X9838Y994729D03*
X34544Y192540D03*
X34480Y202243D03*
X29191Y210428D03*
Y207428D03*
X22170Y246150D03*
X14791Y247715D03*
X17782Y248150D03*
X29390Y246960D03*
X26040Y245190D03*
X29291Y235093D03*
X26791D03*
X31871D03*
X26791Y232593D03*
X29331D03*
X31871D03*
X14587Y231944D03*
X17087D03*
X19667D03*
Y229444D03*
X17127D03*
X14587D03*
X12791Y261000D03*
X17953Y267500D03*
X21500D03*
X32716Y273500D03*
X24000Y276000D03*
X18185Y312228D03*
X21185D03*
Y315228D03*
X18185D03*
X24185Y312228D03*
X27185D03*
Y315228D03*
X24185D03*
X26500Y358728D03*
X23500D03*
X20500D03*
X17500D03*
Y361728D03*
X26500D03*
X20500D03*
X23500D03*
X11000Y502000D03*
Y511000D03*
X10987Y523418D03*
X20452Y513547D03*
X27580Y528341D03*
X29500Y534075D03*
X28900Y556900D03*
X30380Y648320D03*
X32720Y660000D03*
X32258Y646000D03*
X21000Y644000D03*
X32760Y657000D03*
X21525Y660000D03*
Y654000D03*
X12389Y653509D03*
X12512Y647013D03*
X25023Y663850D03*
X14925Y663000D03*
X21525Y666500D03*
X32760Y669500D03*
X21525Y672500D03*
X32760Y682000D03*
X25023Y669850D03*
X32728Y679000D03*
X12500D03*
X14925Y669000D03*
Y690000D03*
X13000Y709000D03*
X20453Y708047D03*
X15713Y710009D03*
X20327Y711174D03*
X17500Y734000D03*
X13375Y730274D03*
X17500Y741000D03*
Y748000D03*
X12819Y751500D03*
X15012Y745563D03*
X17458Y737184D03*
X12419Y765261D03*
X14830Y763614D03*
X23000Y760000D03*
X13500Y862500D03*
X32525Y904241D03*
Y907241D03*
X32825Y917841D03*
Y914841D03*
X32625Y925241D03*
Y928241D03*
X27587Y937815D03*
Y934815D03*
X31871Y961865D03*
X26791D03*
X29291D03*
X31871Y959365D03*
X29331D03*
X26791D03*
X14587Y958716D03*
X17087D03*
X19667D03*
Y956216D03*
X17127D03*
X14587D03*
X26990Y975034D03*
X14791Y976000D03*
X17500Y974500D03*
X28791Y976919D03*
X27886Y972134D03*
X23702Y992261D03*
X20000Y989000D03*
X23009Y995491D03*
X30522Y1000288D03*
X15000Y1001300D03*
X24685Y1041800D03*
X18185Y1041900D03*
X21385D03*
X24685Y1038800D03*
X21385Y1038900D03*
X18185D03*
X13492Y1049256D03*
Y1051756D03*
Y1046676D03*
X25000Y1104300D03*
X22000D03*
X19000D03*
Y1107300D03*
X22000D03*
X25000D03*
X19500Y1239500D03*
X12150Y1227850D03*
X47399Y149664D03*
X44399D03*
Y152164D03*
X47399D03*
Y146864D03*
X44399D03*
X34380Y179643D03*
X47487Y171264D03*
X44487D03*
Y174264D03*
X47487D03*
X34380Y182643D03*
X34544Y189540D03*
X34480Y199243D03*
X36880Y249217D03*
X42309Y251270D03*
X50967Y246228D03*
X53967D03*
X48477Y233457D03*
X51477D03*
X54477D03*
X39167Y230228D03*
X42167D03*
X51456Y230214D03*
X48456D03*
X54456D03*
X41864Y265636D03*
X38880Y263169D03*
X44500Y272767D03*
X38383Y280119D03*
X40472Y283287D03*
X55650Y280728D03*
X40500Y295500D03*
X53343Y301334D03*
X44500Y301500D03*
X52000Y298528D03*
X57430Y298520D03*
X50021Y313863D03*
X52561D03*
Y311363D03*
X50061D03*
X47481D03*
Y313863D03*
X37185Y316228D03*
X40185D03*
X53000Y345997D03*
Y348497D03*
Y350997D03*
X55700Y342500D03*
X53000Y364997D03*
Y367497D03*
Y369997D03*
X49689Y474203D03*
X56925Y503000D03*
Y528500D03*
Y508500D03*
Y523500D03*
Y518500D03*
X57000Y538500D03*
X47499Y649000D03*
X52977Y662650D03*
X56475Y654000D03*
X46950Y666500D03*
X56475Y672500D03*
X46950D03*
X52977Y681650D03*
X34000Y757000D03*
X37000Y756900D03*
X38900Y800200D03*
X52800Y813500D03*
X47813Y833013D03*
X48308Y877415D03*
Y880415D03*
Y883415D03*
X50808Y877415D03*
Y880415D03*
Y883415D03*
X48631Y964607D03*
Y962107D03*
X48731Y959507D03*
Y957007D03*
X42167Y958400D03*
X39167D03*
X48731Y972307D03*
Y974807D03*
X48631Y969707D03*
Y967207D03*
X35259Y968798D03*
X38500Y977199D03*
X40500Y995000D03*
X39061Y1005000D03*
X40972Y1010059D03*
X38880Y989941D03*
X48492Y1006856D03*
X51852Y1012249D03*
X42000Y1023000D03*
X44100Y1027850D03*
X50000Y1023000D03*
X53000Y1026000D03*
X40585Y1041300D03*
X37585D03*
X50561Y1038135D03*
X53061D03*
Y1040635D03*
X50521D03*
X47981D03*
Y1038135D03*
X55700Y1079289D03*
Y1075878D03*
X55701Y1071860D03*
Y1068449D03*
X55635Y1090665D03*
Y1094076D03*
X40500Y1164000D03*
X68416Y63842D03*
X60475Y79692D03*
X61000Y84192D03*
X68500Y70000D03*
X64025Y92575D03*
X65350Y102000D03*
X76000Y133500D03*
X71500Y130000D03*
X76743Y116500D03*
X56967Y246228D03*
X72500Y283771D03*
X64500Y287000D03*
X58561Y280728D03*
X66561Y273985D03*
X71689Y302000D03*
X64561Y298446D03*
X61420Y299310D03*
X64765Y314512D03*
Y317012D03*
X62265Y314512D03*
X62225Y317012D03*
X59685D03*
Y314512D03*
X78500Y406000D03*
X65900Y413000D03*
X60475Y424728D03*
Y429228D03*
X67000Y430500D03*
X71000Y427000D03*
X58500Y454500D03*
X79500Y449925D03*
X58500Y441000D03*
X65350Y447500D03*
X70500Y443500D03*
X68000Y463878D03*
X71300Y460000D03*
X57000Y483000D03*
X56925Y498000D03*
Y493000D03*
Y488000D03*
Y513500D03*
X79293Y523513D03*
X75650Y517770D03*
X56925Y533500D03*
X68345Y533265D03*
X76500Y531476D03*
X72500Y541500D03*
X75396Y544500D03*
X73747Y570715D03*
X74000Y608425D03*
X56475Y641000D03*
X78457Y634010D03*
X78677Y637315D03*
X63070Y652400D03*
X56475Y647000D03*
Y660000D03*
X68000Y664000D03*
X56475Y666500D03*
Y679000D03*
Y685000D03*
X69000Y669745D03*
X68000Y676500D03*
X59475Y688975D03*
X76500Y704000D03*
Y709500D03*
X60000Y696984D03*
X69350Y711940D03*
X68100Y721000D03*
X61500Y728500D03*
X70925Y732000D03*
X76475Y715000D03*
X65570Y734500D03*
X74075Y721500D03*
Y726500D03*
X76475Y742500D03*
X70925Y749000D03*
X58612Y740500D03*
X76725Y749500D03*
X66000Y776000D03*
X61576Y762200D03*
X69000Y771500D03*
X77400Y775000D03*
X62058Y801075D03*
X60000Y797925D03*
X71500Y805500D03*
X77000Y819000D03*
X67993Y827764D03*
X65350Y818654D03*
X77000Y823500D03*
X68000Y804606D03*
X71410Y846500D03*
X75500Y852500D03*
X73000Y1010500D03*
X56150Y1007500D03*
X72000Y1013500D03*
X59268Y1007793D03*
X69802Y1006198D03*
X74000Y1026000D03*
X66000Y1025000D03*
X62500Y1025500D03*
X60185Y1043784D03*
X62725D03*
X65265D03*
Y1041284D03*
X62765D03*
X60185D03*
X61029Y1064153D03*
Y1060742D03*
X64231Y1115268D03*
X77518Y1138500D03*
X68686Y1139993D03*
X76500Y1162975D03*
X60475Y1152000D03*
X61500Y1160000D03*
X79000Y1157425D03*
Y1173425D03*
X64425Y1165500D03*
X64843Y1194000D03*
X79106Y1176575D03*
X75000Y1196500D03*
X64850Y1179000D03*
X76400Y1188100D03*
X82975Y53333D03*
X84400Y64200D03*
X99000Y61000D03*
X99883Y57500D03*
X87500Y83300D03*
X79500Y86925D03*
X80500Y74000D03*
X88802Y100198D03*
X86000Y92000D03*
X94430Y103830D03*
X79500Y104425D03*
X88900Y119300D03*
X82500Y389500D03*
Y398000D03*
X79463Y429962D03*
X91500Y434000D03*
X82000Y415000D03*
X100835Y446500D03*
X91593Y439000D03*
X95000Y462740D03*
X96502Y501930D03*
X84575Y487075D03*
X95184Y493787D03*
X98040Y506730D03*
X87500Y522800D03*
X98925Y515000D03*
X96275Y519750D03*
X98925Y534000D03*
X82000Y531476D03*
X87500D03*
X93000D03*
X84723Y532202D03*
X102075Y534000D03*
X84050Y555925D03*
X85000Y562148D03*
X100505Y561919D03*
X97000Y569153D03*
X90680Y561766D03*
X98780Y617000D03*
X99051Y635051D03*
X87500Y634700D03*
X88300Y639800D03*
X103037Y624462D03*
X91532Y663261D03*
X95032Y660000D03*
X86000Y676000D03*
Y684000D03*
X101284Y671500D03*
X101309Y675500D03*
X86000Y700000D03*
X79975Y739975D03*
X99279Y781942D03*
X99500Y787000D03*
X83000Y804000D03*
X94000Y825740D03*
Y818500D03*
X101500Y824271D03*
X83000Y810000D03*
X84000Y844950D03*
X99000Y848000D03*
X104500Y834500D03*
X80000Y828500D03*
X102500Y979500D03*
X79500Y1134000D03*
X91000Y1173425D03*
X81000Y1193425D03*
X86000Y1176575D03*
X111522Y39800D03*
X114522D03*
X111522Y44800D03*
X114522D03*
X111522Y47300D03*
Y49800D03*
X114522D03*
Y52300D03*
X111522D03*
X114522Y47300D03*
X111522Y42300D03*
X114522D03*
X123500Y59500D03*
X118475Y83500D03*
X115918Y75650D03*
X112000Y88700D03*
X122500Y102000D03*
X123500Y115500D03*
X103000Y136500D03*
X127482Y312228D03*
X107000Y389500D03*
Y400425D03*
X118500Y403500D03*
X107966Y408260D03*
X110000Y392500D03*
X117500Y398500D03*
X110500Y445000D03*
X106850Y441596D03*
X104500Y478500D03*
X122000Y463000D03*
X118490Y495330D03*
X124500Y485000D03*
X119000D03*
X113500D03*
X109000Y500000D03*
X105760Y493500D03*
X104500Y483425D03*
X126070Y493931D03*
X112070Y499790D03*
X109000Y485000D03*
X113500Y523000D03*
X111000Y506000D03*
X108500Y512000D03*
X108000Y539500D03*
X109000Y543500D03*
X111000Y555925D03*
X115788Y573787D03*
X125000Y562500D03*
X106977Y561919D03*
X121500Y557500D03*
X120000Y581500D03*
X108601Y627084D03*
X118079Y639954D03*
X106000Y634500D03*
X124499Y660000D03*
X126185Y688915D03*
X123401Y669102D03*
X117500Y689900D03*
X119500Y707500D03*
X118000Y696000D03*
X119500Y715500D03*
X115525Y731000D03*
X119000Y734000D03*
X125075Y715000D03*
X115525Y745000D03*
Y738000D03*
X112294Y754294D03*
X125352Y749277D03*
X114857Y741500D03*
X121536Y749253D03*
X121841Y775967D03*
X119836Y761664D03*
X125654Y772281D03*
X107365Y776004D03*
X118711Y797500D03*
X120500Y845000D03*
X123000Y829114D03*
X117500Y857575D03*
X119500Y992000D03*
X127182Y1039000D03*
X110000Y1128425D03*
X121000Y1131575D03*
X124500Y1148575D03*
X109500Y1139500D03*
X123500Y1137500D03*
X118000Y1151575D03*
X123000Y1181000D03*
X127000Y77500D03*
X142000Y74575D03*
X132350Y94273D03*
X142500Y103342D03*
X142000Y98842D03*
X138650Y94000D03*
X132500Y99000D03*
X135000Y120500D03*
X137449Y113340D03*
X135750Y132750D03*
X127500Y129500D03*
X141890Y246451D03*
X128000Y251000D03*
X137495Y248875D03*
X138198Y231944D03*
X140778D03*
X143358D03*
Y229444D03*
X140818D03*
X138238D03*
X133529Y265385D03*
X147393Y265728D03*
X136500Y261000D03*
X144482Y265728D03*
X142400Y269800D03*
X147500Y278228D03*
X136482Y272471D03*
X133482Y315228D03*
Y312228D03*
X130482Y315228D03*
Y312228D03*
X146482Y316228D03*
X127482Y315228D03*
X144600Y337100D03*
Y339828D03*
X135245Y407228D03*
X132850Y421837D03*
X130500Y432500D03*
X139150Y420193D03*
Y429650D03*
X135000Y463000D03*
X129000Y468000D03*
X135500Y485024D03*
X130000Y485025D03*
X148000Y483000D03*
X150575Y504500D03*
X144324Y498325D03*
X145193Y504232D03*
X141500Y516500D03*
X144335Y509166D03*
X138532Y507500D03*
X150575Y534500D03*
X128500Y554925D03*
X135500Y562500D03*
X133491Y560490D03*
X131500Y634500D03*
X135000Y637500D03*
X150300Y645900D03*
X141900Y645410D03*
X128000Y694500D03*
X133575Y692000D03*
X139150Y712500D03*
X136500Y728500D03*
X128065Y725566D03*
X136500Y742000D03*
X133900Y776000D03*
X129285Y781799D03*
X128500Y791500D03*
X132370Y788872D03*
X128500Y786500D03*
X139650Y785905D03*
X139075Y801984D03*
X134800Y826614D03*
X138428Y806903D03*
X141088Y804709D03*
X133246Y811300D03*
X142999Y842350D03*
X148281Y838882D03*
X145600Y838100D03*
X146000Y854500D03*
X138278Y961865D03*
X140778D03*
X143358D03*
Y959365D03*
X140818D03*
X138278D03*
X129112Y978769D03*
X142000Y977500D03*
X138605Y977649D03*
X146644Y1007363D03*
X133529Y995306D03*
X136482Y1002392D03*
X147393Y995649D03*
X147229Y1004299D03*
X139435Y989500D03*
X144482Y995649D03*
X149500Y1023000D03*
X127182Y1055000D03*
Y1042000D03*
X133382Y1055000D03*
Y1042000D03*
Y1039000D03*
X130382Y1055000D03*
Y1042000D03*
Y1039000D03*
X146482Y1043000D03*
X143072Y1073000D03*
Y1075500D03*
Y1078000D03*
X141572Y1067900D03*
Y1070400D03*
X143072Y1092500D03*
Y1095000D03*
Y1097500D03*
X132175Y1117325D03*
X127000Y1143000D03*
X135800Y1138000D03*
X138650Y1149500D03*
X127000Y1157025D03*
Y1166000D03*
X142500Y1161500D03*
X138650Y1165500D03*
X126360Y1185947D03*
X136800Y1194800D03*
X142500Y1176000D03*
X148576Y146649D03*
X151576D03*
Y149149D03*
X148576D03*
X154576Y146649D03*
Y149149D03*
X149664Y174443D03*
Y171443D03*
Y168443D03*
Y165443D03*
X165164Y186143D03*
Y189143D03*
X164964Y199543D03*
Y196543D03*
X164864Y208443D03*
Y205443D03*
X168564Y217543D03*
Y214543D03*
X150500Y247000D03*
X153022Y232593D03*
X150482D03*
X155562D03*
X165562Y230593D03*
X163022D03*
X150482Y235093D03*
X152982D03*
X155562D03*
X152500Y249501D03*
X161200Y251200D03*
X159430Y244830D03*
X165014Y268287D03*
X161105Y266081D03*
X149769Y283287D03*
X164947Y280728D03*
X152420Y296500D03*
X167000Y296310D03*
X169358Y286228D03*
X167858Y279310D03*
X160777Y275688D03*
X149500Y295500D03*
X160000Y298500D03*
X170358Y298858D03*
X156778Y311363D03*
Y313863D03*
X159318D03*
X161858D03*
Y311363D03*
X159358D03*
X149482Y316228D03*
X162783Y301463D03*
X168982Y314512D03*
X171562D03*
X171522Y317012D03*
X168982D03*
X158858Y329228D03*
Y332228D03*
X149900Y346300D03*
Y349028D03*
Y351800D03*
Y364300D03*
Y370300D03*
Y367528D03*
X151635Y476202D03*
X154000Y471000D03*
X150575Y494500D03*
Y499500D03*
X150500Y489500D03*
X150575Y524500D03*
Y519500D03*
Y509500D03*
X153725Y524500D03*
Y514500D03*
X169000Y535075D03*
X150500Y544500D03*
X150575Y539500D03*
Y529500D03*
X167190Y529510D03*
X171977Y656850D03*
X166547Y663500D03*
X159051Y671661D03*
X167679Y674254D03*
X167642Y682217D03*
X169475Y706000D03*
X167060Y692500D03*
X171440Y708767D03*
X169475Y733000D03*
Y713000D03*
Y720000D03*
X171586Y735683D03*
X171580Y716500D03*
X163925Y756500D03*
X169475Y747000D03*
Y740000D03*
X171500Y743500D03*
X172000Y751500D03*
X149000Y854500D03*
X152364Y890115D03*
Y893115D03*
Y896115D03*
X149864Y890115D03*
Y893115D03*
Y896115D03*
X162877Y910500D03*
Y913500D03*
Y931500D03*
Y934500D03*
Y921500D03*
Y924500D03*
X168177Y940100D03*
X153622Y962514D03*
X151082D03*
Y965014D03*
X153582D03*
X156162D03*
Y962514D03*
X167858Y961800D03*
X164858D03*
X168177Y943100D03*
X149658Y974968D03*
X159000Y972500D03*
X152823Y978573D03*
X160732Y977966D03*
X164600Y998649D03*
X161581Y995673D03*
X149769Y1010059D03*
X164947Y1007500D03*
X167858D03*
X164337Y1002475D03*
X169358Y1013000D03*
X161884Y1026048D03*
X170929Y1024429D03*
X159500Y1023000D03*
X153150Y1028430D03*
X149482Y1043000D03*
X156778Y1038135D03*
Y1040635D03*
X159318D03*
X161858D03*
Y1038135D03*
X159358D03*
X168982Y1043784D03*
X171522D03*
X171562Y1041284D03*
X168982D03*
X164000Y1171500D03*
X165500Y1229900D03*
X179358Y230328D03*
Y227328D03*
X182358Y230328D03*
X185358D03*
X182358Y227328D03*
X185358D03*
X185658Y243528D03*
X182658D03*
X179658D03*
X178811Y281071D03*
X175858Y273985D03*
X173858Y298500D03*
X183500Y299500D03*
X174062Y314512D03*
Y317012D03*
X176858Y359790D03*
Y362290D03*
X185858Y359790D03*
X182858D03*
Y362290D03*
X185858D03*
X179858Y359790D03*
Y362290D03*
X189500Y512000D03*
X191575Y524000D03*
X188516Y518310D03*
X179000Y531925D03*
X189250Y541750D03*
X191991Y536336D03*
X194000Y550000D03*
X191500Y529500D03*
X191259Y547500D03*
X182500Y641600D03*
X187500Y643500D03*
X176000Y659500D03*
X175500Y651500D03*
X180500Y684500D03*
X182500Y688000D03*
X177500Y679500D03*
X175500Y672500D03*
X175475Y668500D03*
X179000Y676500D03*
X187925Y701000D03*
X181000Y696500D03*
X179000Y694000D03*
X190300Y725200D03*
X187041Y730000D03*
X193000Y754500D03*
X191000Y756500D03*
X184425Y738000D03*
X189000Y758500D03*
X173200Y770800D03*
X180658Y956100D03*
X186658D03*
Y952900D03*
X180658D03*
X183758Y956200D03*
Y953000D03*
X180658Y969000D03*
X186658D03*
X183758Y969100D03*
X178811Y1007843D03*
X175858Y1000757D03*
X182058Y1022519D03*
X173858Y1025500D03*
X174062Y1043784D03*
Y1041284D03*
X186458Y1103662D03*
X183458D03*
X180458D03*
X186458Y1106662D03*
X180458D03*
X183458D03*
X192000Y1240500D03*
X182600Y1228850D03*
X195000Y752500D03*
G54D27*
X42717Y620713D03*
X101772Y204370D03*
Y952401D03*
X160827Y620713D03*
G54D24*
X14791Y210028D03*
Y207028D03*
X25545Y248578D03*
X27912Y270676D03*
X32000Y261000D03*
X10000Y267303D03*
X11700Y907753D03*
Y904753D03*
Y918753D03*
Y915753D03*
X12053Y937268D03*
Y934268D03*
X11700Y928753D03*
Y925753D03*
X25500Y977500D03*
X31791Y993000D03*
X26500Y997500D03*
X15275Y995500D03*
X39167Y244728D03*
X42167D03*
X55167Y259228D03*
X52167D03*
X55167Y272228D03*
Y256328D03*
X52167D03*
X45500Y646000D03*
X45240Y657000D03*
Y669500D03*
Y682000D03*
X42367Y972800D03*
X39367D03*
X61300Y66900D03*
X69100Y76100D03*
X71650Y94259D03*
Y111259D03*
X62716Y129542D03*
X75500Y130000D03*
X58167Y259228D03*
X61167D03*
X58167Y272228D03*
X61167D03*
X64167D03*
X58167Y256328D03*
X61167D03*
X68700Y400000D03*
X78500Y410000D03*
X62216Y412678D03*
X69018Y420378D03*
X74979Y437559D03*
X65250Y470378D03*
X65475Y666500D03*
X65500Y671500D03*
X65475Y685000D03*
Y679000D03*
X58673Y775800D03*
X77816Y764764D03*
X78000Y782500D03*
X68694Y764764D03*
X68481Y800951D03*
X69018Y783764D03*
X62216Y830875D03*
X77018Y836764D03*
X65367Y996400D03*
X62367D03*
X56367D03*
X59367D03*
X62216Y1139950D03*
X77518Y1142650D03*
X68543Y1128650D03*
X77816D03*
X69018Y1147650D03*
X71150Y1165500D03*
X74313Y1178559D03*
X73505Y1200075D03*
X84500Y404000D03*
X139435Y266728D03*
X145982Y268287D03*
X139435Y996649D03*
X145982Y998208D03*
X165858Y244728D03*
X162858D03*
X155482Y266228D03*
X149000Y250000D03*
X156962Y692037D03*
X164758Y976500D03*
X167758D03*
X151000Y981000D03*
X155482Y996149D03*
X183582Y217228D03*
Y214228D03*
X181258Y269528D03*
X184258D03*
X187258D03*
X178258D03*
X181067Y256528D03*
X184067D03*
X187067D03*
X178067D03*
X180967Y253728D03*
X177967D03*
X183967D03*
X186967D03*
X187050Y652000D03*
Y659500D03*
Y663500D03*
X184377Y910500D03*
Y913500D03*
X183177Y940100D03*
X184377Y931500D03*
Y934500D03*
Y921500D03*
Y924500D03*
X183177Y943100D03*
X187658Y995000D03*
Y998000D03*
X184658Y995000D03*
Y998000D03*
X181658Y995000D03*
Y998000D03*
X190158Y995000D03*
Y998000D03*
G54D29*
X73300Y340600D03*
Y338100D03*
X74700Y346000D03*
Y351000D03*
Y348500D03*
X74428Y370500D03*
Y368000D03*
Y365500D03*
X76526Y1075845D03*
X76464Y1079181D03*
Y1072947D03*
X76526Y1069611D03*
X75860Y1064323D03*
X75893Y1061138D03*
X76431Y1094565D03*
X76493Y1091229D03*
X112500Y76000D03*
X113000Y394500D03*
X112441Y418434D03*
X107500Y782530D03*
X121072Y1077500D03*
Y1075000D03*
Y1072500D03*
Y1094500D03*
Y1092000D03*
Y1097000D03*
X121000Y1128425D03*
X112941Y1146240D03*
X130200Y339900D03*
Y337400D03*
X126760Y1071023D03*
X126793Y1067838D03*
G54D23*
X13080Y179343D03*
Y182343D03*
Y192843D03*
Y189843D03*
X13580Y201643D03*
Y198643D03*
G54D25*
X18000Y491500D03*
X20500Y497500D03*
Y495000D03*
G54D21*
X34252Y64606D03*
Y56732D03*
Y48858D03*
X26378Y64606D03*
Y56732D03*
Y48858D03*
X34252Y88228D03*
Y80354D03*
X26378Y88228D03*
Y72480D03*
X34252Y103976D03*
Y96102D03*
X26378Y103976D03*
Y96102D03*
X34252Y412244D03*
X26378D03*
X34252Y427992D03*
Y420118D03*
X26378Y435866D03*
Y427992D03*
Y420118D03*
X34252Y451614D03*
Y443740D03*
X26378Y451614D03*
X34252Y467362D03*
Y459488D03*
X26378Y467362D03*
Y459488D03*
X34252Y775630D03*
X26378D03*
X34252Y791378D03*
Y783504D03*
X26378Y799252D03*
Y791378D03*
Y783504D03*
X34252Y822874D03*
Y815000D03*
Y807126D03*
X26378Y822874D03*
Y815000D03*
X34252Y830748D03*
X26378D03*
X34252Y1146890D03*
Y1139016D03*
X26378Y1146890D03*
Y1139016D03*
X34252Y1170512D03*
Y1154764D03*
X26378Y1162638D03*
Y1154764D03*
X34252Y1194134D03*
Y1186260D03*
Y1178386D03*
X26378Y1194134D03*
Y1186260D03*
Y1178386D03*
X169291Y48858D03*
Y56732D03*
Y64606D03*
Y72480D03*
Y88228D03*
Y96102D03*
Y103976D03*
Y412244D03*
Y420118D03*
Y427992D03*
Y435866D03*
Y451614D03*
Y459488D03*
Y467362D03*
Y775630D03*
Y783504D03*
Y791378D03*
Y799252D03*
Y815000D03*
Y822874D03*
Y830748D03*
Y1139016D03*
Y1146890D03*
Y1154764D03*
Y1162638D03*
Y1178386D03*
Y1186260D03*
Y1194134D03*
X177165Y48858D03*
Y56732D03*
Y64606D03*
Y80354D03*
Y88228D03*
Y96102D03*
Y103976D03*
Y412244D03*
Y420118D03*
Y427992D03*
Y443740D03*
Y451614D03*
Y459488D03*
Y467362D03*
Y775630D03*
Y783504D03*
Y791378D03*
Y807126D03*
Y815000D03*
Y822874D03*
Y830748D03*
Y1139016D03*
Y1146890D03*
Y1154764D03*
Y1170512D03*
Y1178386D03*
Y1186260D03*
Y1194134D03*
G54D12*
X-63431Y837184D03*
Y1152816D03*
X-53431Y837184D03*
Y1152816D03*
X-32318Y837184D03*
X-22318D03*
X-32318Y1152816D03*
X-22318D03*
G54D20*
X30315Y41378D03*
Y404764D03*
Y768150D03*
Y1131536D03*
X173228Y111456D03*
Y474842D03*
Y838228D03*
Y1201614D03*
G54D30*
X101772Y1287047D03*
G54D31*
X169291Y80354D03*
Y443740D03*
Y807126D03*
Y1170512D03*
X177165Y72480D03*
Y435866D03*
Y799252D03*
Y1162638D03*
G54D14*
X-27318Y824000D03*
G54D11*
X-58431D03*
G54D10*
X-58189Y19685D03*
Y619685D03*
Y1307087D03*
X865353Y19685D03*
Y1307087D03*
G54D28*
X20000Y1307000D03*
X44000Y17500D03*
X178500D03*
G54D16*
X3005Y30675D03*
Y50675D03*
Y70675D03*
Y90675D03*
Y110675D03*
Y130675D03*
Y150675D03*
Y170675D03*
X8908Y163243D03*
Y160243D03*
X3005Y190675D03*
Y210675D03*
Y230675D03*
Y250675D03*
Y270675D03*
Y290675D03*
Y310675D03*
Y330675D03*
Y350675D03*
Y370675D03*
Y390675D03*
Y410675D03*
Y430675D03*
Y450675D03*
Y470675D03*
Y490675D03*
Y510675D03*
Y530675D03*
Y550675D03*
Y570675D03*
Y590675D03*
Y610675D03*
Y630675D03*
Y650675D03*
Y670675D03*
Y690675D03*
Y710675D03*
Y730675D03*
Y750675D03*
Y770675D03*
Y790675D03*
Y810675D03*
Y830675D03*
Y850675D03*
Y870675D03*
Y890675D03*
Y910675D03*
Y930675D03*
Y950675D03*
Y970675D03*
Y990675D03*
Y1010675D03*
Y1030675D03*
Y1050675D03*
Y1070675D03*
Y1090675D03*
Y1110675D03*
Y1130675D03*
Y1150675D03*
Y1170675D03*
Y1190675D03*
Y1210675D03*
Y1230675D03*
Y1250675D03*
Y1270675D03*
Y1290675D03*
Y1310675D03*
X15868Y3010D03*
X11874Y154893D03*
X13708Y173943D03*
Y170943D03*
X11208Y173943D03*
Y170943D03*
X29500Y520500D03*
Y512500D03*
X12800Y870600D03*
X15600D03*
X12864Y873315D03*
Y876315D03*
Y879315D03*
X15664D03*
Y876315D03*
Y873315D03*
X16017Y1323770D03*
X34927Y3006D03*
X54927D03*
X37500Y520500D03*
Y512500D03*
X51164Y988115D03*
Y985115D03*
X48664D03*
Y988115D03*
X51164Y994115D03*
Y991115D03*
X48664D03*
Y994115D03*
X35517Y1323770D03*
X56017D03*
X61802Y25927D03*
X68508Y50969D03*
X78500Y512500D03*
Y504500D03*
X73500Y562200D03*
X74857Y611575D03*
X76017Y1323770D03*
X91059Y94630D03*
Y452760D03*
X85500Y472975D03*
X86500Y512500D03*
Y504500D03*
X92950Y821707D03*
X82000Y833575D03*
X94730Y1173910D03*
X96017Y1323770D03*
X120000Y512500D03*
Y504500D03*
X114000Y591000D03*
X116017Y1323770D03*
X146740Y3016D03*
X141748Y26922D03*
X135014Y50977D03*
X128000Y512500D03*
Y504500D03*
X136017Y1323770D03*
X165799Y3002D03*
X169000Y522000D03*
Y514000D03*
X156017Y1323770D03*
X185799Y3002D03*
X193719Y157489D03*
X191219D03*
X192164Y164843D03*
X189664D03*
X192164Y167843D03*
X189664D03*
X192164Y170843D03*
X189664D03*
X192164Y173843D03*
X189664D03*
X186964Y189043D03*
Y186043D03*
Y199543D03*
Y196543D03*
X186764Y208743D03*
Y205743D03*
X177000Y522000D03*
Y514000D03*
X193964Y887015D03*
Y890015D03*
Y893015D03*
Y896015D03*
X180264Y895915D03*
Y892915D03*
Y889915D03*
X193964Y899015D03*
X180264Y898915D03*
X176017Y1323770D03*
X194471Y1321882D03*
X199120Y9903D03*
X200536Y29059D03*
Y49059D03*
Y69059D03*
Y109059D03*
Y89059D03*
Y129059D03*
Y149059D03*
Y169059D03*
Y189059D03*
Y209059D03*
Y249059D03*
Y229059D03*
Y269059D03*
Y289059D03*
Y309059D03*
Y329059D03*
Y349059D03*
Y369059D03*
Y409059D03*
Y389059D03*
Y429059D03*
Y449059D03*
Y469059D03*
Y489059D03*
Y509059D03*
Y549059D03*
Y529059D03*
Y569059D03*
Y589059D03*
Y609059D03*
Y629059D03*
Y649059D03*
Y669059D03*
Y709059D03*
Y689059D03*
Y729059D03*
Y749059D03*
Y769059D03*
Y789059D03*
Y809059D03*
Y849059D03*
Y829059D03*
Y869059D03*
Y889059D03*
Y909059D03*
Y929059D03*
Y947059D03*
Y969059D03*
Y1009059D03*
Y989059D03*
Y1029059D03*
Y1049059D03*
Y1069059D03*
Y1089059D03*
Y1109059D03*
Y1149059D03*
Y1129059D03*
Y1169059D03*
Y1189059D03*
Y1209059D03*
Y1229059D03*
Y1249059D03*
Y1289059D03*
Y1269059D03*
Y1309059D03*
G54D18*
X6025Y734000D03*
X6000Y727000D03*
X6025Y748000D03*
Y741000D03*
X27185Y286228D03*
X21185D03*
X24185D03*
X27185Y289228D03*
X21185D03*
X24185D03*
X18185Y286228D03*
Y289228D03*
X14000Y335928D03*
X17000D03*
X20000D03*
X23000D03*
X26000D03*
X11000Y520000D03*
Y515500D03*
Y506500D03*
X26500Y732500D03*
X13425Y712500D03*
X16985Y1028800D03*
X19985D03*
Y1015800D03*
X16985D03*
X19985Y1012800D03*
X16985D03*
X22985Y1028800D03*
X25985D03*
Y1015800D03*
X22985D03*
X25985Y1012800D03*
X22985D03*
X26000Y1062720D03*
X23000D03*
X20000D03*
X17000D03*
X14000D03*
X10241Y1234150D03*
X11000Y1239500D03*
X23500Y1237000D03*
X47561Y280228D03*
X40185Y301728D03*
X37185D03*
X54926Y296651D03*
X49250Y516750D03*
X35484Y534075D03*
X33500Y694425D03*
X48005Y1012038D03*
X37555Y1027168D03*
X40555D03*
X53000Y1021500D03*
X56000Y1203273D03*
X78400Y40200D03*
Y36700D03*
Y33200D03*
Y47200D03*
Y43700D03*
X75173Y78000D03*
X61500Y97500D03*
X58700Y110900D03*
X56730Y278169D03*
X77773Y420228D03*
X60773Y443728D03*
Y457228D03*
X74500Y475000D03*
X74626Y515080D03*
X68500Y537075D03*
X66400Y655400D03*
X65552Y645503D03*
X74075Y732000D03*
X76500Y746500D03*
X61000Y810000D03*
X60773Y820614D03*
X71650Y821000D03*
X64108Y1006500D03*
X56245Y1004000D03*
X77773Y1147500D03*
X61000Y1172500D03*
X57500Y1181000D03*
X85500Y40000D03*
Y36500D03*
Y33000D03*
Y47000D03*
Y43500D03*
X86500Y481500D03*
X98925Y524000D03*
Y512500D03*
X83300Y624100D03*
X86000Y680000D03*
Y688000D03*
Y696000D03*
X93000Y731000D03*
X93025Y738000D03*
X93000Y745000D03*
X99000Y853000D03*
X122917Y39800D03*
Y37300D03*
Y49800D03*
Y47300D03*
Y44800D03*
Y42300D03*
X114500Y127000D03*
X127482Y286228D03*
X124378Y409308D03*
X125200Y453800D03*
X113500Y476000D03*
X105815Y488500D03*
X105732Y496844D03*
X116000Y529500D03*
X126500Y706500D03*
X115563Y759063D03*
X125500Y820114D03*
X125227Y815000D03*
X126000Y834500D03*
X126500Y1129000D03*
X125000Y1198000D03*
X125917Y39800D03*
Y37300D03*
Y49800D03*
Y47300D03*
Y44800D03*
Y42300D03*
X135500Y70441D03*
X142727Y79842D03*
Y94000D03*
X134525Y107842D03*
X141327Y115542D03*
X125500Y118000D03*
X127482Y289228D03*
X133482D03*
X130482D03*
X136482D03*
X133482Y286228D03*
X130482D03*
X136482D03*
X146482Y301728D03*
X128000Y348300D03*
X127900Y345100D03*
Y364300D03*
Y351800D03*
X127800Y370900D03*
X127900Y367900D03*
X141327Y398000D03*
X136000Y429941D03*
X129314Y414545D03*
X145327Y416500D03*
X142727Y428000D03*
X125500Y469600D03*
X135349Y468652D03*
X134000Y501000D03*
X134575Y659000D03*
X146000Y729000D03*
X127983Y736234D03*
X144827Y763510D03*
X129705Y777796D03*
X132350Y793241D03*
X142727Y791500D03*
X141993Y800295D03*
X141327Y822814D03*
X134525Y815114D03*
X131882Y1012900D03*
X134882D03*
X131882Y1015900D03*
X134882D03*
X125882Y1012900D03*
X128882D03*
X125882Y1015900D03*
X128882D03*
X146482Y1028500D03*
X141649Y1141500D03*
X135500Y1143441D03*
X142088Y1131281D03*
X132350Y1156741D03*
X142727Y1151000D03*
X142500Y1183500D03*
X125440Y1175970D03*
X135000Y1197500D03*
X156858Y280228D03*
X166499Y276483D03*
X149482Y301728D03*
X164296Y297723D03*
X170000Y504500D03*
X169000Y542075D03*
X167075Y756500D03*
X151300Y756400D03*
X149500Y850500D03*
X156858Y1007000D03*
X166358Y1004941D03*
X149482Y1028500D03*
X162500Y1023000D03*
X172905Y279728D03*
X177458Y335828D03*
X180458D03*
X186458D03*
X183458D03*
X191575Y518500D03*
X179000Y535075D03*
X181475Y713000D03*
X193475Y706000D03*
X181475Y720000D03*
X192582Y733000D03*
X181475Y740000D03*
Y747000D03*
X182285Y982200D03*
X179285D03*
X188285D03*
X185285D03*
X172905Y1006500D03*
X190358Y1062764D03*
X187358D03*
X184358D03*
X181358D03*
Y1060064D03*
X184358D03*
X187358D03*
X190358D03*
X192500Y1215000D03*
X182741Y1235150D03*
X183500Y1240500D03*
X195000Y490500D03*
X195500Y495000D03*
Y497500D03*
Y1220000D03*
Y1222500D03*
G54D19*
X8000Y1220000D03*
Y1222500D03*
X11000Y1215000D03*
G54D22*
X34252Y72480D03*
X26378Y80354D03*
X34252Y435866D03*
X26378Y443740D03*
X34252Y799252D03*
X26378Y807126D03*
X34252Y1162638D03*
X26378Y1170512D03*
G54D13*
X-58431Y1166000D03*
G54D15*
X-27318D03*
%LPC*%
G75*
G54D32*
G01X-320500Y-470483D02*
Y2626000D01*
X2967000D01*
Y-470483D01*
X-320500D01*
G01X329322Y-314459D02*
Y-319459D01*
G01X327865Y-314459D02*
X330779D01*
G01X335689Y-319459D02*
X333155D01*
Y-314459D01*
X335689D01*
G01X334675Y-316876D02*
X333155D01*
G01X338255Y-314459D02*
Y-319459D01*
X340789D01*
G01X344622Y-319626D02*
X344495Y-319542D01*
Y-319376D01*
X344622Y-319292D01*
X344749Y-319376D01*
Y-319542D01*
X344622Y-319626D01*
G01Y-317376D02*
X344495Y-317292D01*
Y-317126D01*
X344622Y-317042D01*
X344749Y-317126D01*
Y-317292D01*
X344622Y-317376D01*
G01X349405Y-321126D02*
X348772Y-320292D01*
X348455Y-319459D01*
Y-316126D01*
X348772Y-315292D01*
X349405Y-314459D01*
G01X354822D02*
X354315Y-314626D01*
X353935Y-315042D01*
X353682Y-315542D01*
X353492Y-316209D01*
X353429Y-316959D01*
X353492Y-317709D01*
X353682Y-318376D01*
X353935Y-318876D01*
X354315Y-319292D01*
X354822Y-319459D01*
X355329Y-319292D01*
X355709Y-318876D01*
X355962Y-318376D01*
X356152Y-317709D01*
X356215Y-316959D01*
X356152Y-316209D01*
X355962Y-315542D01*
X355709Y-315042D01*
X355329Y-314626D01*
X354822Y-314459D01*
G01X358529Y-318459D02*
X358909Y-319042D01*
X359415Y-319376D01*
X359985Y-319459D01*
X360492Y-319376D01*
X360999Y-318959D01*
X361315Y-318459D01*
X361379Y-317959D01*
X361252Y-317376D01*
X360809Y-316959D01*
X360365Y-316792D01*
X359795D01*
G01X360365D02*
X360745Y-316542D01*
X361062Y-316126D01*
X361189Y-315626D01*
X361062Y-315126D01*
X360745Y-314709D01*
X360175Y-314459D01*
X359605Y-314542D01*
X359035Y-314876D01*
G01X365339Y-321126D02*
X365972Y-320292D01*
X366289Y-319459D01*
Y-316126D01*
X365972Y-315292D01*
X365339Y-314459D01*
G01X368729Y-318459D02*
X369109Y-319042D01*
X369615Y-319376D01*
X370185Y-319459D01*
X370692Y-319376D01*
X371199Y-318959D01*
X371515Y-318459D01*
X371579Y-317959D01*
X371452Y-317376D01*
X371009Y-316959D01*
X370565Y-316792D01*
X369995D01*
G01X370565D02*
X370945Y-316542D01*
X371262Y-316126D01*
X371389Y-315626D01*
X371262Y-315126D01*
X370945Y-314709D01*
X370375Y-314459D01*
X369805Y-314542D01*
X369235Y-314876D01*
G01X374019Y-315292D02*
X374399Y-314792D01*
X374842Y-314542D01*
X375349Y-314459D01*
X375982Y-314626D01*
X376425Y-315042D01*
X376552Y-315542D01*
X376489Y-316042D01*
X376235Y-316459D01*
X374969Y-317292D01*
X374399Y-317876D01*
X374019Y-318709D01*
X373892Y-319459D01*
X376552D01*
G01X380195D02*
X380322Y-318376D01*
X380512Y-317459D01*
X380765Y-316626D01*
X381082Y-315709D01*
X381589Y-314459D01*
X379055D01*
G01X384599Y-317792D02*
X386245D01*
G01X389319Y-315292D02*
X389699Y-314792D01*
X390142Y-314542D01*
X390649Y-314459D01*
X391282Y-314626D01*
X391725Y-315042D01*
X391852Y-315542D01*
X391789Y-316042D01*
X391535Y-316459D01*
X390269Y-317292D01*
X389699Y-317876D01*
X389319Y-318709D01*
X389192Y-319459D01*
X391852D01*
G01X394229Y-318459D02*
X394609Y-319042D01*
X395115Y-319376D01*
X395685Y-319459D01*
X396192Y-319376D01*
X396699Y-318959D01*
X397015Y-318459D01*
X397079Y-317959D01*
X396952Y-317376D01*
X396509Y-316959D01*
X396065Y-316792D01*
X395495D01*
G01X396065D02*
X396445Y-316542D01*
X396762Y-316126D01*
X396889Y-315626D01*
X396762Y-315126D01*
X396445Y-314709D01*
X395875Y-314459D01*
X395305Y-314542D01*
X394735Y-314876D01*
G01X401482Y-319459D02*
Y-314459D01*
X399139Y-318042D01*
X402305D01*
G01X404429Y-318709D02*
X404809Y-319126D01*
X405252Y-319376D01*
X405822Y-319459D01*
X406392Y-319292D01*
X406835Y-318959D01*
X407152Y-318376D01*
X407215Y-317709D01*
X407089Y-317042D01*
X406772Y-316626D01*
X406329Y-316292D01*
X405885Y-316209D01*
X405442Y-316292D01*
X404872Y-316626D01*
X405062Y-314459D01*
X406772D01*
G01X414819Y-319459D02*
Y-314459D01*
X417225D01*
G01X416339Y-316876D02*
X414819D01*
G01X419539Y-319459D02*
X421122Y-314459D01*
X422705Y-319459D01*
G01X422135Y-317709D02*
X420109D01*
G01X424892Y-319459D02*
X427552Y-314459D01*
G01X424892D02*
X427552Y-319459D01*
G01X431322Y-319626D02*
X431195Y-319542D01*
Y-319376D01*
X431322Y-319292D01*
X431449Y-319376D01*
Y-319542D01*
X431322Y-319626D01*
G01Y-317376D02*
X431195Y-317292D01*
Y-317126D01*
X431322Y-317042D01*
X431449Y-317126D01*
Y-317292D01*
X431322Y-317376D01*
G01X436105Y-321126D02*
X435472Y-320292D01*
X435155Y-319459D01*
Y-316126D01*
X435472Y-315292D01*
X436105Y-314459D01*
G01X441522D02*
X441015Y-314626D01*
X440635Y-315042D01*
X440382Y-315542D01*
X440192Y-316209D01*
X440129Y-316959D01*
X440192Y-317709D01*
X440382Y-318376D01*
X440635Y-318876D01*
X441015Y-319292D01*
X441522Y-319459D01*
X442029Y-319292D01*
X442409Y-318876D01*
X442662Y-318376D01*
X442852Y-317709D01*
X442915Y-316959D01*
X442852Y-316209D01*
X442662Y-315542D01*
X442409Y-315042D01*
X442029Y-314626D01*
X441522Y-314459D01*
G01X445229Y-318459D02*
X445609Y-319042D01*
X446115Y-319376D01*
X446685Y-319459D01*
X447192Y-319376D01*
X447699Y-318959D01*
X448015Y-318459D01*
X448079Y-317959D01*
X447952Y-317376D01*
X447509Y-316959D01*
X447065Y-316792D01*
X446495D01*
G01X447065D02*
X447445Y-316542D01*
X447762Y-316126D01*
X447889Y-315626D01*
X447762Y-315126D01*
X447445Y-314709D01*
X446875Y-314459D01*
X446305Y-314542D01*
X445735Y-314876D01*
G01X452039Y-321126D02*
X452672Y-320292D01*
X452989Y-319459D01*
Y-316126D01*
X452672Y-315292D01*
X452039Y-314459D01*
G01X455429Y-318459D02*
X455809Y-319042D01*
X456315Y-319376D01*
X456885Y-319459D01*
X457392Y-319376D01*
X457899Y-318959D01*
X458215Y-318459D01*
X458279Y-317959D01*
X458152Y-317376D01*
X457709Y-316959D01*
X457265Y-316792D01*
X456695D01*
G01X457265D02*
X457645Y-316542D01*
X457962Y-316126D01*
X458089Y-315626D01*
X457962Y-315126D01*
X457645Y-314709D01*
X457075Y-314459D01*
X456505Y-314542D01*
X455935Y-314876D01*
G01X460845Y-318876D02*
X461289Y-319292D01*
X461795Y-319459D01*
X462302Y-319292D01*
X462745Y-318792D01*
X463062Y-318042D01*
X463189Y-317292D01*
Y-316376D01*
X463062Y-315626D01*
X462745Y-314959D01*
X462365Y-314626D01*
X461922Y-314459D01*
X461415Y-314626D01*
X461035Y-314959D01*
X460782Y-315459D01*
X460655Y-316126D01*
X460782Y-316709D01*
X461099Y-317292D01*
X461479Y-317626D01*
X461922Y-317709D01*
X462429Y-317542D01*
X462809Y-317126D01*
X463189Y-316376D01*
G01X466895Y-319459D02*
X467022Y-318376D01*
X467212Y-317459D01*
X467465Y-316626D01*
X467782Y-315709D01*
X468289Y-314459D01*
X465755D01*
G01X471299Y-317792D02*
X472945D01*
G01X475829Y-318459D02*
X476209Y-319042D01*
X476715Y-319376D01*
X477285Y-319459D01*
X477792Y-319376D01*
X478299Y-318959D01*
X478615Y-318459D01*
X478679Y-317959D01*
X478552Y-317376D01*
X478109Y-316959D01*
X477665Y-316792D01*
X477095D01*
G01X477665D02*
X478045Y-316542D01*
X478362Y-316126D01*
X478489Y-315626D01*
X478362Y-315126D01*
X478045Y-314709D01*
X477475Y-314459D01*
X476905Y-314542D01*
X476335Y-314876D01*
G01X481119Y-317376D02*
X481562Y-316792D01*
X481942Y-316459D01*
X482449Y-316292D01*
X482892Y-316459D01*
X483209Y-316792D01*
X483462Y-317292D01*
X483525Y-317876D01*
X483462Y-318376D01*
X483209Y-318876D01*
X482829Y-319292D01*
X482385Y-319459D01*
X481879Y-319292D01*
X481435Y-318792D01*
X481182Y-318042D01*
X481119Y-317209D01*
X481245Y-316126D01*
X481435Y-315542D01*
X481752Y-314959D01*
X482195Y-314542D01*
X482639Y-314459D01*
X483082Y-314626D01*
X483399Y-315042D01*
G01X487422Y-319459D02*
Y-314459D01*
X486662Y-315459D01*
G01Y-319459D02*
X488182D01*
G01X493282D02*
Y-314459D01*
X490939Y-318042D01*
X494105D01*
G01X317322Y-249459D02*
Y-324459D01*
X817322D01*
Y-249459D01*
X317322D01*
G01X512322D02*
Y-324459D01*
G01Y-299459D02*
X615322D01*
Y-274459D01*
G01X512322D02*
X615322D01*
G01X622829Y-309459D02*
Y-304459D01*
X624095D01*
X624602Y-304709D01*
X624982Y-305042D01*
X625299Y-305542D01*
X625552Y-306126D01*
X625615Y-306959D01*
X625552Y-307792D01*
X625299Y-308376D01*
X624982Y-308876D01*
X624602Y-309209D01*
X624095Y-309459D01*
X622829D01*
G01X627739D02*
X629322Y-304459D01*
X630905Y-309459D01*
G01X630335Y-307709D02*
X628309D01*
G01X634422Y-304459D02*
Y-309459D01*
G01X632965Y-304459D02*
X635879D01*
G01X640789Y-309459D02*
X638255D01*
Y-304459D01*
X640789D01*
G01X639775Y-306876D02*
X638255D01*
G01X644622Y-309626D02*
X644495Y-309542D01*
Y-309376D01*
X644622Y-309292D01*
X644749Y-309376D01*
Y-309542D01*
X644622Y-309626D01*
G01Y-307376D02*
X644495Y-307292D01*
Y-307126D01*
X644622Y-307042D01*
X644749Y-307126D01*
Y-307292D01*
X644622Y-307376D01*
G01X617322Y-249459D02*
Y-324459D01*
G01X615322Y-249459D02*
Y-324459D01*
G01X622955Y-284459D02*
Y-279459D01*
X624475D01*
X624982Y-279709D01*
X625362Y-280292D01*
X625489Y-280959D01*
X625362Y-281626D01*
X625045Y-282126D01*
X624475Y-282376D01*
X622955D01*
G01X628182Y-284626D02*
X630462Y-279459D01*
G01X632965Y-284459D02*
Y-279459D01*
X635879Y-284459D01*
Y-279459D01*
G01X639522Y-284626D02*
X639395Y-284542D01*
Y-284376D01*
X639522Y-284292D01*
X639649Y-284376D01*
Y-284542D01*
X639522Y-284626D01*
G01Y-282376D02*
X639395Y-282292D01*
Y-282126D01*
X639522Y-282042D01*
X639649Y-282126D01*
Y-282292D01*
X639522Y-282376D01*
G01X617322Y-299459D02*
X817322D01*
G01X622955Y-259459D02*
Y-254459D01*
X624475D01*
X624982Y-254709D01*
X625362Y-255292D01*
X625489Y-255959D01*
X625362Y-256626D01*
X625045Y-257126D01*
X624475Y-257376D01*
X622955D01*
G01X628055Y-259459D02*
Y-254459D01*
X629639D01*
X630145Y-254709D01*
X630462Y-255042D01*
X630589Y-255709D01*
X630462Y-256376D01*
X630082Y-256792D01*
X629639Y-257042D01*
X628055D01*
G01X629639D02*
X630589Y-259459D01*
G01X634422D02*
X633915Y-259376D01*
X633472Y-259042D01*
X633092Y-258542D01*
X632839Y-257959D01*
X632712Y-257292D01*
Y-256626D01*
X632839Y-255959D01*
X633092Y-255376D01*
X633472Y-254876D01*
X633915Y-254542D01*
X634422Y-254459D01*
X634929Y-254542D01*
X635372Y-254876D01*
X635752Y-255376D01*
X636005Y-255959D01*
X636132Y-256626D01*
Y-257292D01*
X636005Y-257959D01*
X635752Y-258542D01*
X635372Y-259042D01*
X634929Y-259376D01*
X634422Y-259459D01*
G01X638255Y-258459D02*
X638572Y-258959D01*
X638952Y-259292D01*
X639395Y-259459D01*
X639902Y-259292D01*
X640282Y-258959D01*
X640662Y-258459D01*
X640789Y-257792D01*
Y-254459D01*
G01X645889Y-259459D02*
X643355D01*
Y-254459D01*
X645889D01*
G01X644875Y-256876D02*
X643355D01*
G01X651115Y-254876D02*
X650735Y-254626D01*
X650292Y-254459D01*
X649785D01*
X649215Y-254709D01*
X648772Y-255126D01*
X648455Y-255626D01*
X648202Y-256459D01*
X648139Y-257209D01*
X648265Y-257959D01*
X648455Y-258459D01*
X648835Y-258959D01*
X649279Y-259292D01*
X649722Y-259459D01*
X650165D01*
X650609Y-259292D01*
X650989Y-259042D01*
X651305Y-258709D01*
G01X654822Y-254459D02*
Y-259459D01*
G01X653365Y-254459D02*
X656279D01*
G01X659922Y-259626D02*
X659795Y-259542D01*
Y-259376D01*
X659922Y-259292D01*
X660049Y-259376D01*
Y-259542D01*
X659922Y-259626D01*
G01Y-257376D02*
X659795Y-257292D01*
Y-257126D01*
X659922Y-257042D01*
X660049Y-257126D01*
Y-257292D01*
X659922Y-257376D01*
G01X617322Y-274459D02*
X817322D01*
G01X734955Y-301959D02*
Y-306959D01*
X737489D01*
G01X740562Y-301959D02*
X742082D01*
G01X741322D02*
Y-306959D01*
G01X740562D02*
X742082D01*
G01X746929Y-304292D02*
X747182Y-304042D01*
X747372Y-303626D01*
X747499Y-303042D01*
X747372Y-302542D01*
X747119Y-302209D01*
X746675Y-301959D01*
X744965D01*
Y-306959D01*
X747055D01*
X747499Y-306626D01*
X747752Y-306126D01*
X747879Y-305542D01*
X747752Y-304959D01*
X747372Y-304459D01*
X746929Y-304292D01*
X744965D01*
G01X751522Y-307126D02*
X751395Y-307042D01*
Y-306876D01*
X751522Y-306792D01*
X751649Y-306876D01*
Y-307042D01*
X751522Y-307126D01*
G01Y-304876D02*
X751395Y-304792D01*
Y-304626D01*
X751522Y-304542D01*
X751649Y-304626D01*
Y-304792D01*
X751522Y-304876D01*
G01X732322Y-299459D02*
Y-324459D01*
G01X779222Y-301959D02*
Y-306959D01*
G01X777765Y-301959D02*
X780679D01*
G01X784322Y-306959D02*
X783942Y-306876D01*
X783562Y-306542D01*
X783309Y-305959D01*
X783182Y-305292D01*
X783309Y-304626D01*
X783562Y-304042D01*
X783942Y-303709D01*
X784322Y-303626D01*
X784702Y-303709D01*
X785082Y-304042D01*
X785335Y-304626D01*
X785399Y-305292D01*
X785335Y-305959D01*
X785082Y-306542D01*
X784702Y-306876D01*
X784322Y-306959D01*
G01X789422D02*
X789042Y-306876D01*
X788662Y-306542D01*
X788409Y-305959D01*
X788282Y-305292D01*
X788409Y-304626D01*
X788662Y-304042D01*
X789042Y-303709D01*
X789422Y-303626D01*
X789802Y-303709D01*
X790182Y-304042D01*
X790435Y-304626D01*
X790499Y-305292D01*
X790435Y-305959D01*
X790182Y-306542D01*
X789802Y-306876D01*
X789422Y-306959D01*
G01X794522D02*
Y-301959D01*
G01X799622Y-307126D02*
X799495Y-307042D01*
Y-306876D01*
X799622Y-306792D01*
X799749Y-306876D01*
Y-307042D01*
X799622Y-307126D01*
G01Y-304876D02*
X799495Y-304792D01*
Y-304626D01*
X799622Y-304542D01*
X799749Y-304626D01*
Y-304792D01*
X799622Y-304876D01*
G01X775322Y-299459D02*
Y-324459D01*
G01Y-274459D02*
Y-299459D01*
G01X777955Y-281959D02*
Y-276959D01*
X779539D01*
X780045Y-277209D01*
X780362Y-277542D01*
X780489Y-278209D01*
X780362Y-278876D01*
X779982Y-279292D01*
X779539Y-279542D01*
X777955D01*
G01X779539D02*
X780489Y-281959D01*
G01X785589D02*
X783055D01*
Y-276959D01*
X785589D01*
G01X784575Y-279376D02*
X783055D01*
G01X787839Y-276959D02*
X789422Y-281959D01*
X791005Y-276959D01*
G01X794522Y-282126D02*
X794395Y-282042D01*
Y-281876D01*
X794522Y-281792D01*
X794649Y-281876D01*
Y-282042D01*
X794522Y-282126D01*
G01Y-279876D02*
X794395Y-279792D01*
Y-279626D01*
X794522Y-279542D01*
X794649Y-279626D01*
Y-279792D01*
X794522Y-279876D01*
G01X798082Y-326159D02*
X798162Y-326084D01*
X798222Y-325959D01*
X798262Y-325784D01*
X798222Y-325634D01*
X798142Y-325534D01*
X798002Y-325459D01*
X797462D01*
Y-326959D01*
X798122D01*
X798262Y-326859D01*
X798342Y-326709D01*
X798382Y-326534D01*
X798342Y-326359D01*
X798222Y-326209D01*
X798082Y-326159D01*
X797462D01*
G01X799482Y-326959D02*
Y-325959D01*
G01Y-326134D02*
X799402Y-326034D01*
X799282Y-325984D01*
X799142Y-325959D01*
X799002Y-326009D01*
X798882Y-326109D01*
X798802Y-326259D01*
X798762Y-326459D01*
X798802Y-326659D01*
X798882Y-326809D01*
X799002Y-326909D01*
X799142Y-326959D01*
X799282Y-326934D01*
X799402Y-326859D01*
X799482Y-326759D01*
G01X800022Y-326784D02*
X800122Y-326884D01*
X800262Y-326959D01*
X800382D01*
X800502Y-326909D01*
X800582Y-326834D01*
X800622Y-326734D01*
X800602Y-326584D01*
X800522Y-326509D01*
X800162Y-326359D01*
X800082Y-326184D01*
X800122Y-326059D01*
X800202Y-325984D01*
X800322Y-325959D01*
X800442Y-325984D01*
X800562Y-326059D01*
G01X801222Y-326284D02*
X801862D01*
X801802Y-326109D01*
X801702Y-326009D01*
X801562Y-325959D01*
X801422Y-325984D01*
X801302Y-326059D01*
X801222Y-326234D01*
X801182Y-326384D01*
Y-326534D01*
X801222Y-326684D01*
X801322Y-326834D01*
X801442Y-326934D01*
X801582Y-326959D01*
X801722Y-326909D01*
X801862Y-326759D01*
G01X802362Y-326959D02*
Y-325459D01*
G01Y-326209D02*
X802462Y-326059D01*
X802582Y-325984D01*
X802702Y-325959D01*
X802882Y-326009D01*
X803002Y-326109D01*
X803082Y-326284D01*
Y-326484D01*
X803042Y-326684D01*
X802962Y-326834D01*
X802822Y-326934D01*
X802702Y-326959D01*
X802582Y-326934D01*
X802462Y-326859D01*
X802362Y-326734D01*
G01X803922Y-326959D02*
X803802Y-326934D01*
X803682Y-326834D01*
X803602Y-326659D01*
X803562Y-326459D01*
X803602Y-326259D01*
X803682Y-326084D01*
X803802Y-325984D01*
X803922Y-325959D01*
X804042Y-325984D01*
X804162Y-326084D01*
X804242Y-326259D01*
X804262Y-326459D01*
X804242Y-326659D01*
X804162Y-326834D01*
X804042Y-326934D01*
X803922Y-326959D01*
G01X805482D02*
Y-325959D01*
G01Y-326134D02*
X805402Y-326034D01*
X805282Y-325984D01*
X805142Y-325959D01*
X805002Y-326009D01*
X804882Y-326109D01*
X804802Y-326259D01*
X804762Y-326459D01*
X804802Y-326659D01*
X804882Y-326809D01*
X805002Y-326909D01*
X805142Y-326959D01*
X805282Y-326934D01*
X805402Y-326859D01*
X805482Y-326759D01*
G01X806042Y-326959D02*
Y-325959D01*
G01Y-326159D02*
X806142Y-326059D01*
X806242Y-325984D01*
X806382Y-325959D01*
X806482Y-325984D01*
X806602Y-326059D01*
G01X807882Y-325459D02*
Y-326959D01*
G01Y-326734D02*
X807802Y-326859D01*
X807682Y-326934D01*
X807542Y-326959D01*
X807382Y-326909D01*
X807262Y-326784D01*
X807182Y-326634D01*
X807162Y-326459D01*
X807182Y-326284D01*
X807262Y-326134D01*
X807382Y-326009D01*
X807542Y-325959D01*
X807682Y-325984D01*
X807782Y-326034D01*
X807882Y-326134D01*
G01X809522Y-326959D02*
Y-325459D01*
X810022D01*
X810182Y-325534D01*
X810282Y-325634D01*
X810322Y-325834D01*
X810282Y-326034D01*
X810162Y-326159D01*
X810022Y-326234D01*
X809522D01*
G01X810022D02*
X810322Y-326959D01*
G01X810822Y-326284D02*
X811462D01*
X811402Y-326109D01*
X811302Y-326009D01*
X811162Y-325959D01*
X811022Y-325984D01*
X810902Y-326059D01*
X810822Y-326234D01*
X810782Y-326384D01*
Y-326534D01*
X810822Y-326684D01*
X810922Y-326834D01*
X811042Y-326934D01*
X811182Y-326959D01*
X811322Y-326909D01*
X811462Y-326759D01*
G01X811962Y-325959D02*
X812322Y-326959D01*
X812682Y-325959D01*
G01X813522Y-327009D02*
X813482Y-326984D01*
Y-326934D01*
X813522Y-326909D01*
X813562Y-326934D01*
Y-326984D01*
X813522Y-327009D01*
G01X814682Y-326959D02*
X814722Y-326634D01*
X814782Y-326359D01*
X814862Y-326109D01*
X814962Y-325834D01*
X815122Y-325459D01*
X814322D01*
G01X816082Y-326159D02*
X816162Y-326084D01*
X816222Y-325959D01*
X816262Y-325784D01*
X816222Y-325634D01*
X816142Y-325534D01*
X816002Y-325459D01*
X815462D01*
Y-326959D01*
X816122D01*
X816262Y-326859D01*
X816342Y-326709D01*
X816382Y-326534D01*
X816342Y-326359D01*
X816222Y-326209D01*
X816082Y-326159D01*
X815462D01*
G01X-320500Y-470483D02*
Y2626000D01*
X2967000D01*
Y-470483D01*
X-320500D01*
G01X331395Y-304184D02*
X330925Y-303869D01*
X330377Y-303659D01*
X329750D01*
X329045Y-303974D01*
X328497Y-304499D01*
X328105Y-305129D01*
X327792Y-306179D01*
X327714Y-307124D01*
X327870Y-308069D01*
X328105Y-308699D01*
X328575Y-309329D01*
X329124Y-309749D01*
X329672Y-309959D01*
X330220D01*
X330769Y-309749D01*
X331239Y-309434D01*
X331630Y-309014D01*
G01X335032Y-303659D02*
X336912D01*
G01X335972D02*
Y-309959D01*
G01X335032D02*
X336912D01*
G01X342272Y-303659D02*
Y-309959D01*
G01X340470Y-303659D02*
X344074D01*
G01X348572Y-309959D02*
Y-307124D01*
X347005Y-303659D01*
G01X350139D02*
X348572Y-307124D01*
G01X359449Y-308699D02*
X359919Y-309434D01*
X360545Y-309854D01*
X361250Y-309959D01*
X361877Y-309854D01*
X362504Y-309329D01*
X362895Y-308699D01*
X362974Y-308069D01*
X362817Y-307334D01*
X362269Y-306809D01*
X361720Y-306599D01*
X361015D01*
G01X361720D02*
X362190Y-306284D01*
X362582Y-305759D01*
X362739Y-305129D01*
X362582Y-304499D01*
X362190Y-303974D01*
X361485Y-303659D01*
X360780Y-303764D01*
X360075Y-304184D01*
G01X365749Y-308699D02*
X366219Y-309434D01*
X366845Y-309854D01*
X367550Y-309959D01*
X368177Y-309854D01*
X368804Y-309329D01*
X369195Y-308699D01*
X369274Y-308069D01*
X369117Y-307334D01*
X368569Y-306809D01*
X368020Y-306599D01*
X367315D01*
G01X368020D02*
X368490Y-306284D01*
X368882Y-305759D01*
X369039Y-305129D01*
X368882Y-304499D01*
X368490Y-303974D01*
X367785Y-303659D01*
X367080Y-303764D01*
X366375Y-304184D01*
G01X372049Y-308699D02*
X372519Y-309434D01*
X373145Y-309854D01*
X373850Y-309959D01*
X374477Y-309854D01*
X375104Y-309329D01*
X375495Y-308699D01*
X375574Y-308069D01*
X375417Y-307334D01*
X374869Y-306809D01*
X374320Y-306599D01*
X373615D01*
G01X374320D02*
X374790Y-306284D01*
X375182Y-305759D01*
X375339Y-305129D01*
X375182Y-304499D01*
X374790Y-303974D01*
X374085Y-303659D01*
X373380Y-303764D01*
X372675Y-304184D01*
G01X379915Y-309959D02*
X380072Y-308594D01*
X380307Y-307439D01*
X380620Y-306389D01*
X381012Y-305234D01*
X381639Y-303659D01*
X378505D01*
G01X386215Y-309959D02*
X386372Y-308594D01*
X386607Y-307439D01*
X386920Y-306389D01*
X387312Y-305234D01*
X387939Y-303659D01*
X384805D01*
G01X392515Y-311114D02*
X392829Y-309749D01*
G01X398972Y-303659D02*
Y-309959D01*
G01X397170Y-303659D02*
X400774D01*
G01X403314Y-309959D02*
X405272Y-303659D01*
X407230Y-309959D01*
G01X406525Y-307754D02*
X404019D01*
G01X410632Y-303659D02*
X412512D01*
G01X411572D02*
Y-309959D01*
G01X410632D02*
X412512D01*
G01X415522Y-303659D02*
X416619Y-309959D01*
X417872Y-303659D01*
X419125Y-309959D01*
X420222Y-303659D01*
G01X422214Y-309959D02*
X424172Y-303659D01*
X426130Y-309959D01*
G01X425425Y-307754D02*
X422919D01*
G01X428670Y-309959D02*
Y-303659D01*
X432274Y-309959D01*
Y-303659D01*
G01X442680Y-312059D02*
X441897Y-311009D01*
X441505Y-309959D01*
Y-305759D01*
X441897Y-304709D01*
X442680Y-303659D01*
G01X454105Y-309959D02*
Y-303659D01*
X456064D01*
X456690Y-303974D01*
X457082Y-304394D01*
X457239Y-305234D01*
X457082Y-306074D01*
X456612Y-306599D01*
X456064Y-306914D01*
X454105D01*
G01X456064D02*
X457239Y-309959D01*
G01X461972Y-310169D02*
X461815Y-310064D01*
Y-309854D01*
X461972Y-309749D01*
X462129Y-309854D01*
Y-310064D01*
X461972Y-310169D01*
G01X468272Y-309959D02*
X467645Y-309854D01*
X467097Y-309434D01*
X466627Y-308804D01*
X466314Y-308069D01*
X466157Y-307229D01*
Y-306389D01*
X466314Y-305549D01*
X466627Y-304814D01*
X467097Y-304184D01*
X467645Y-303764D01*
X468272Y-303659D01*
X468899Y-303764D01*
X469447Y-304184D01*
X469917Y-304814D01*
X470230Y-305549D01*
X470387Y-306389D01*
Y-307229D01*
X470230Y-308069D01*
X469917Y-308804D01*
X469447Y-309434D01*
X468899Y-309854D01*
X468272Y-309959D01*
G01X474572Y-310169D02*
X474415Y-310064D01*
Y-309854D01*
X474572Y-309749D01*
X474729Y-309854D01*
Y-310064D01*
X474572Y-310169D01*
G01X482595Y-304184D02*
X482125Y-303869D01*
X481577Y-303659D01*
X480950D01*
X480245Y-303974D01*
X479697Y-304499D01*
X479305Y-305129D01*
X478992Y-306179D01*
X478914Y-307124D01*
X479070Y-308069D01*
X479305Y-308699D01*
X479775Y-309329D01*
X480324Y-309749D01*
X480872Y-309959D01*
X481420D01*
X481969Y-309749D01*
X482439Y-309434D01*
X482830Y-309014D01*
G01X487172Y-310169D02*
X487015Y-310064D01*
Y-309854D01*
X487172Y-309749D01*
X487329Y-309854D01*
Y-310064D01*
X487172Y-310169D01*
G01X493864Y-312059D02*
X494647Y-311009D01*
X495039Y-309959D01*
Y-305759D01*
X494647Y-304709D01*
X493864Y-303659D01*
G01X330142Y-296809D02*
X331709D01*
Y-298699D01*
X331239Y-299329D01*
X330690Y-299749D01*
X329907Y-299959D01*
X329124Y-299749D01*
X328575Y-299329D01*
X328105Y-298699D01*
X327792Y-297964D01*
X327635Y-297124D01*
Y-296389D01*
X327792Y-295759D01*
X328105Y-295024D01*
X328575Y-294394D01*
X329045Y-293974D01*
X329672Y-293659D01*
X330220D01*
X330847Y-293869D01*
X331317Y-294289D01*
G01X334249Y-293659D02*
Y-298174D01*
X334562Y-299119D01*
X335189Y-299749D01*
X335972Y-299959D01*
X336755Y-299749D01*
X337382Y-299119D01*
X337695Y-298174D01*
Y-293659D01*
G01X341332D02*
X343212D01*
G01X342272D02*
Y-299959D01*
G01X341332D02*
X343212D01*
G01X346927Y-299119D02*
X347554Y-299644D01*
X348259Y-299959D01*
X348885D01*
X349512Y-299644D01*
X349982Y-299119D01*
X350217Y-298384D01*
X350060Y-297649D01*
X349669Y-297019D01*
X348964Y-296599D01*
X348024Y-296389D01*
X347475Y-295969D01*
X347240Y-295234D01*
X347397Y-294499D01*
X347789Y-293974D01*
X348337Y-293659D01*
X348885D01*
X349434Y-293869D01*
X349904Y-294394D01*
G01X353227Y-299959D02*
Y-293659D01*
G01X356517D02*
Y-299959D01*
G01Y-296809D02*
X353227D01*
G01X359214Y-299959D02*
X361172Y-293659D01*
X363130Y-299959D01*
G01X362425Y-297754D02*
X359919D01*
G01X365670Y-299959D02*
Y-293659D01*
X369274Y-299959D01*
Y-293659D01*
G01X378349Y-299959D02*
Y-293659D01*
X379915D01*
X380542Y-293974D01*
X381012Y-294394D01*
X381404Y-295024D01*
X381717Y-295759D01*
X381795Y-296809D01*
X381717Y-297859D01*
X381404Y-298594D01*
X381012Y-299224D01*
X380542Y-299644D01*
X379915Y-299959D01*
X378349D01*
G01X385432Y-293659D02*
X387312D01*
G01X386372D02*
Y-299959D01*
G01X385432D02*
X387312D01*
G01X391027Y-299119D02*
X391654Y-299644D01*
X392359Y-299959D01*
X392985D01*
X393612Y-299644D01*
X394082Y-299119D01*
X394317Y-298384D01*
X394160Y-297649D01*
X393769Y-297019D01*
X393064Y-296599D01*
X392124Y-296389D01*
X391575Y-295969D01*
X391340Y-295234D01*
X391497Y-294499D01*
X391889Y-293974D01*
X392437Y-293659D01*
X392985D01*
X393534Y-293869D01*
X394004Y-294394D01*
G01X398972Y-293659D02*
Y-299959D01*
G01X397170Y-293659D02*
X400774D01*
G01X405272Y-300169D02*
X405115Y-300064D01*
Y-299854D01*
X405272Y-299749D01*
X405429Y-299854D01*
Y-300064D01*
X405272Y-300169D01*
G01X411415Y-301114D02*
X411729Y-299749D01*
G01X417872Y-293659D02*
Y-299959D01*
G01X416070Y-293659D02*
X419674D01*
G01X422214Y-299959D02*
X424172Y-293659D01*
X426130Y-299959D01*
G01X425425Y-297754D02*
X422919D01*
G01X430472Y-299959D02*
X429845Y-299854D01*
X429297Y-299434D01*
X428827Y-298804D01*
X428514Y-298069D01*
X428357Y-297229D01*
Y-296389D01*
X428514Y-295549D01*
X428827Y-294814D01*
X429297Y-294184D01*
X429845Y-293764D01*
X430472Y-293659D01*
X431099Y-293764D01*
X431647Y-294184D01*
X432117Y-294814D01*
X432430Y-295549D01*
X432587Y-296389D01*
Y-297229D01*
X432430Y-298069D01*
X432117Y-298804D01*
X431647Y-299434D01*
X431099Y-299854D01*
X430472Y-299959D01*
G01X436772D02*
Y-297124D01*
X435205Y-293659D01*
G01X438339D02*
X436772Y-297124D01*
G01X441349Y-293659D02*
Y-298174D01*
X441662Y-299119D01*
X442289Y-299749D01*
X443072Y-299959D01*
X443855Y-299749D01*
X444482Y-299119D01*
X444795Y-298174D01*
Y-293659D01*
G01X447414Y-299959D02*
X449372Y-293659D01*
X451330Y-299959D01*
G01X450625Y-297754D02*
X448119D01*
G01X453870Y-299959D02*
Y-293659D01*
X457474Y-299959D01*
Y-293659D01*
G01X327870Y-289959D02*
Y-283659D01*
X331474Y-289959D01*
Y-283659D01*
G01X335972Y-289959D02*
X335345Y-289854D01*
X334797Y-289434D01*
X334327Y-288804D01*
X334014Y-288069D01*
X333857Y-287229D01*
Y-286389D01*
X334014Y-285549D01*
X334327Y-284814D01*
X334797Y-284184D01*
X335345Y-283764D01*
X335972Y-283659D01*
X336599Y-283764D01*
X337147Y-284184D01*
X337617Y-284814D01*
X337930Y-285549D01*
X338087Y-286389D01*
Y-287229D01*
X337930Y-288069D01*
X337617Y-288804D01*
X337147Y-289434D01*
X336599Y-289854D01*
X335972Y-289959D01*
G01X342272Y-290169D02*
X342115Y-290064D01*
Y-289854D01*
X342272Y-289749D01*
X342429Y-289854D01*
Y-290064D01*
X342272Y-290169D01*
G01X347084Y-284709D02*
X347554Y-284079D01*
X348102Y-283764D01*
X348729Y-283659D01*
X349512Y-283869D01*
X350060Y-284394D01*
X350217Y-285024D01*
X350139Y-285654D01*
X349825Y-286179D01*
X348259Y-287229D01*
X347554Y-287964D01*
X347084Y-289014D01*
X346927Y-289959D01*
X350217D01*
G01X354872D02*
Y-283659D01*
X353932Y-284919D01*
G01Y-289959D02*
X355812D01*
G01X361172D02*
Y-283659D01*
X360232Y-284919D01*
G01Y-289959D02*
X362112D01*
G01X367315Y-291114D02*
X367629Y-289749D01*
G01X371422Y-283659D02*
X372519Y-289959D01*
X373772Y-283659D01*
X375025Y-289959D01*
X376122Y-283659D01*
G01X381639Y-289959D02*
X378505D01*
Y-283659D01*
X381639D01*
G01X380385Y-286704D02*
X378505D01*
G01X384570Y-289959D02*
Y-283659D01*
X388174Y-289959D01*
Y-283659D01*
G01X391027Y-289959D02*
Y-283659D01*
G01X394317D02*
Y-289959D01*
G01Y-286809D02*
X391027D01*
G01X397249Y-283659D02*
Y-288174D01*
X397562Y-289119D01*
X398189Y-289749D01*
X398972Y-289959D01*
X399755Y-289749D01*
X400382Y-289119D01*
X400695Y-288174D01*
Y-283659D01*
G01X403314Y-289959D02*
X405272Y-283659D01*
X407230Y-289959D01*
G01X406525Y-287754D02*
X404019D01*
G01X416384Y-284709D02*
X416854Y-284079D01*
X417402Y-283764D01*
X418029Y-283659D01*
X418812Y-283869D01*
X419360Y-284394D01*
X419517Y-285024D01*
X419439Y-285654D01*
X419125Y-286179D01*
X417559Y-287229D01*
X416854Y-287964D01*
X416384Y-289014D01*
X416227Y-289959D01*
X419517D01*
G01X422370D02*
Y-283659D01*
X425974Y-289959D01*
Y-283659D01*
G01X428749Y-289959D02*
Y-283659D01*
X430315D01*
X430942Y-283974D01*
X431412Y-284394D01*
X431804Y-285024D01*
X432117Y-285759D01*
X432195Y-286809D01*
X432117Y-287859D01*
X431804Y-288594D01*
X431412Y-289224D01*
X430942Y-289644D01*
X430315Y-289959D01*
X428749D01*
G01X441505D02*
Y-283659D01*
X443464D01*
X444090Y-283974D01*
X444482Y-284394D01*
X444639Y-285234D01*
X444482Y-286074D01*
X444012Y-286599D01*
X443464Y-286914D01*
X441505D01*
G01X443464D02*
X444639Y-289959D01*
G01X447649D02*
Y-283659D01*
X449215D01*
X449842Y-283974D01*
X450312Y-284394D01*
X450704Y-285024D01*
X451017Y-285759D01*
X451095Y-286809D01*
X451017Y-287859D01*
X450704Y-288594D01*
X450312Y-289224D01*
X449842Y-289644D01*
X449215Y-289959D01*
X447649D01*
G01X455672Y-290169D02*
X455515Y-290064D01*
Y-289854D01*
X455672Y-289749D01*
X455829Y-289854D01*
Y-290064D01*
X455672Y-290169D01*
G01X351972Y-279259D02*
X349452Y-278842D01*
X347247Y-277176D01*
X345357Y-274676D01*
X344097Y-271759D01*
X343467Y-268426D01*
Y-265092D01*
X344097Y-261759D01*
X345357Y-258842D01*
X347247Y-256343D01*
X349452Y-254676D01*
X351972Y-254259D01*
X354492Y-254676D01*
X356697Y-256343D01*
X358587Y-258842D01*
X359847Y-261759D01*
X360477Y-265092D01*
Y-268426D01*
X359847Y-271759D01*
X358587Y-274676D01*
X356697Y-277176D01*
X354492Y-278842D01*
X351972Y-279259D01*
G01X354492Y-272592D02*
X358272Y-279259D01*
G01X371817Y-262593D02*
Y-274259D01*
X373077Y-277176D01*
X374967Y-278842D01*
X377172Y-279259D01*
X379377Y-278842D01*
X381267Y-277176D01*
X382527Y-274259D01*
G01Y-279259D02*
Y-262593D01*
G01X408042Y-279259D02*
Y-262593D01*
G01Y-265509D02*
X406782Y-263843D01*
X404892Y-263009D01*
X402687Y-262593D01*
X400482Y-263426D01*
X398592Y-265092D01*
X397332Y-267593D01*
X396702Y-270926D01*
X397332Y-274259D01*
X398592Y-276760D01*
X400482Y-278426D01*
X402687Y-279259D01*
X404892Y-278842D01*
X406782Y-277593D01*
X408042Y-275926D01*
G01X422217Y-279259D02*
Y-262593D01*
G01Y-266759D02*
X423477Y-264676D01*
X425367Y-263009D01*
X427887Y-262593D01*
X430092Y-263009D01*
X431982Y-264676D01*
X432927Y-267593D01*
Y-279259D01*
G01X452772Y-254259D02*
Y-279259D01*
G01X448362Y-262593D02*
X457182D01*
G01X483642Y-279259D02*
Y-262593D01*
G01Y-265509D02*
X482382Y-263843D01*
X480492Y-263009D01*
X478287Y-262593D01*
X476082Y-263426D01*
X474192Y-265092D01*
X472932Y-267593D01*
X472302Y-270926D01*
X472932Y-274259D01*
X474192Y-276760D01*
X476082Y-278426D01*
X478287Y-279259D01*
X480492Y-278842D01*
X482382Y-277593D01*
X483642Y-275926D01*
G01X523322Y-258959D02*
Y-266959D01*
X527322D01*
G01X535122D02*
Y-261626D01*
G01Y-262559D02*
X534722Y-262026D01*
X534122Y-261759D01*
X533422Y-261626D01*
X532722Y-261892D01*
X532122Y-262426D01*
X531722Y-263226D01*
X531522Y-264292D01*
X531722Y-265359D01*
X532122Y-266159D01*
X532722Y-266692D01*
X533422Y-266959D01*
X534122Y-266826D01*
X534722Y-266426D01*
X535122Y-265893D01*
G01X539222Y-269359D02*
X539822Y-269626D01*
X540622Y-269359D01*
X541122Y-268826D01*
X541522Y-268159D01*
X542122Y-266026D01*
X543422Y-261626D01*
G01X540222D02*
X542122Y-266026D01*
G01X547822Y-263359D02*
X551022D01*
X550722Y-262426D01*
X550222Y-261892D01*
X549522Y-261626D01*
X548822Y-261759D01*
X548222Y-262159D01*
X547822Y-263092D01*
X547622Y-263893D01*
Y-264692D01*
X547822Y-265492D01*
X548322Y-266292D01*
X548922Y-266826D01*
X549622Y-266959D01*
X550322Y-266692D01*
X551022Y-265893D01*
G01X555922Y-266959D02*
Y-261626D01*
G01Y-262692D02*
X556422Y-262159D01*
X556922Y-261759D01*
X557622Y-261626D01*
X558122Y-261759D01*
X558722Y-262159D01*
G01X542022Y-316959D02*
Y-308959D01*
X546622Y-316959D01*
Y-308959D01*
G01X552322Y-311626D02*
Y-316959D01*
G01Y-309492D02*
X552122Y-309359D01*
Y-309092D01*
X552322Y-308959D01*
X552522Y-309092D01*
Y-309359D01*
X552322Y-309492D01*
G01X558622Y-316959D02*
Y-311626D01*
G01Y-312959D02*
X559022Y-312292D01*
X559622Y-311759D01*
X560422Y-311626D01*
X561122Y-311759D01*
X561722Y-312292D01*
X562022Y-313226D01*
Y-316959D01*
G01X570122D02*
Y-311626D01*
G01Y-312559D02*
X569722Y-312026D01*
X569122Y-311759D01*
X568422Y-311626D01*
X567722Y-311892D01*
X567122Y-312426D01*
X566722Y-313226D01*
X566522Y-314292D01*
X566722Y-315359D01*
X567122Y-316159D01*
X567722Y-316692D01*
X568422Y-316959D01*
X569122Y-316826D01*
X569722Y-316426D01*
X570122Y-315893D01*
G01X552422Y-287959D02*
X554422D01*
Y-290359D01*
X553822Y-291159D01*
X553122Y-291692D01*
X552122Y-291959D01*
X551122Y-291692D01*
X550422Y-291159D01*
X549822Y-290359D01*
X549422Y-289426D01*
X549222Y-288359D01*
Y-287426D01*
X549422Y-286626D01*
X549822Y-285692D01*
X550422Y-284892D01*
X551022Y-284359D01*
X551822Y-283959D01*
X552522D01*
X553322Y-284226D01*
X553922Y-284759D01*
G01X557522Y-291959D02*
Y-283959D01*
X562122Y-291959D01*
Y-283959D01*
G01X565622Y-291959D02*
Y-283959D01*
X567622D01*
X568422Y-284359D01*
X569022Y-284892D01*
X569522Y-285692D01*
X569922Y-286626D01*
X570022Y-287959D01*
X569922Y-289292D01*
X569522Y-290226D01*
X569022Y-291026D01*
X568422Y-291559D01*
X567622Y-291959D01*
X565622D01*
G01X574922Y-260292D02*
X575522Y-259492D01*
X576222Y-259092D01*
X577022Y-258959D01*
X578022Y-259226D01*
X578722Y-259892D01*
X578922Y-260692D01*
X578822Y-261493D01*
X578422Y-262159D01*
X576422Y-263492D01*
X575522Y-264426D01*
X574922Y-265759D01*
X574722Y-266959D01*
X578922D01*
G01X649922Y-310292D02*
X650522Y-309492D01*
X651222Y-309092D01*
X652022Y-308959D01*
X653022Y-309226D01*
X653722Y-309892D01*
X653922Y-310692D01*
X653822Y-311493D01*
X653422Y-312159D01*
X651422Y-313492D01*
X650522Y-314426D01*
X649922Y-315759D01*
X649722Y-316959D01*
X653922D01*
G01X659822Y-308959D02*
X659022Y-309226D01*
X658422Y-309892D01*
X658022Y-310692D01*
X657722Y-311759D01*
X657622Y-312959D01*
X657722Y-314159D01*
X658022Y-315226D01*
X658422Y-316026D01*
X659022Y-316692D01*
X659822Y-316959D01*
X660622Y-316692D01*
X661222Y-316026D01*
X661622Y-315226D01*
X661922Y-314159D01*
X662022Y-312959D01*
X661922Y-311759D01*
X661622Y-310692D01*
X661222Y-309892D01*
X660622Y-309226D01*
X659822Y-308959D01*
G01X665922Y-310292D02*
X666522Y-309492D01*
X667222Y-309092D01*
X668022Y-308959D01*
X669022Y-309226D01*
X669722Y-309892D01*
X669922Y-310692D01*
X669822Y-311493D01*
X669422Y-312159D01*
X667422Y-313492D01*
X666522Y-314426D01*
X665922Y-315759D01*
X665722Y-316959D01*
X669922D01*
G01X673922Y-310292D02*
X674522Y-309492D01*
X675222Y-309092D01*
X676022Y-308959D01*
X677022Y-309226D01*
X677722Y-309892D01*
X677922Y-310692D01*
X677822Y-311493D01*
X677422Y-312159D01*
X675422Y-313492D01*
X674522Y-314426D01*
X673922Y-315759D01*
X673722Y-316959D01*
X677922D01*
G01X682022Y-317226D02*
X685622Y-308959D01*
G01X691822Y-316959D02*
Y-308959D01*
X690622Y-310559D01*
G01Y-316959D02*
X693022D01*
G01X697922Y-310292D02*
X698522Y-309492D01*
X699222Y-309092D01*
X700022Y-308959D01*
X701022Y-309226D01*
X701722Y-309892D01*
X701922Y-310692D01*
X701822Y-311493D01*
X701422Y-312159D01*
X699422Y-313492D01*
X698522Y-314426D01*
X697922Y-315759D01*
X697722Y-316959D01*
X701922D01*
G01X706022Y-317226D02*
X709622Y-308959D01*
G01X715822D02*
X715022Y-309226D01*
X714422Y-309892D01*
X714022Y-310692D01*
X713722Y-311759D01*
X713622Y-312959D01*
X713722Y-314159D01*
X714022Y-315226D01*
X714422Y-316026D01*
X715022Y-316692D01*
X715822Y-316959D01*
X716622Y-316692D01*
X717222Y-316026D01*
X717622Y-315226D01*
X717922Y-314159D01*
X718022Y-312959D01*
X717922Y-311759D01*
X717622Y-310692D01*
X717222Y-309892D01*
X716622Y-309226D01*
X715822Y-308959D01*
G01X722122Y-316026D02*
X722822Y-316692D01*
X723622Y-316959D01*
X724422Y-316692D01*
X725122Y-315893D01*
X725622Y-314692D01*
X725822Y-313492D01*
Y-312026D01*
X725622Y-310826D01*
X725122Y-309759D01*
X724522Y-309226D01*
X723822Y-308959D01*
X723022Y-309226D01*
X722422Y-309759D01*
X722022Y-310559D01*
X721822Y-311626D01*
X722022Y-312559D01*
X722522Y-313492D01*
X723122Y-314026D01*
X723822Y-314159D01*
X724622Y-313893D01*
X725222Y-313226D01*
X725822Y-312026D01*
G01X649622Y-291959D02*
Y-283959D01*
X651622D01*
X652422Y-284359D01*
X653022Y-284892D01*
X653522Y-285692D01*
X653922Y-286626D01*
X654022Y-287959D01*
X653922Y-289292D01*
X653522Y-290226D01*
X653022Y-291026D01*
X652422Y-291559D01*
X651622Y-291959D01*
X649622D01*
G01X657322D02*
X659822Y-283959D01*
X662322Y-291959D01*
G01X661422Y-289159D02*
X658222D01*
G01X667822Y-283959D02*
X667022Y-284226D01*
X666422Y-284892D01*
X666022Y-285692D01*
X665722Y-286759D01*
X665622Y-287959D01*
X665722Y-289159D01*
X666022Y-290226D01*
X666422Y-291026D01*
X667022Y-291692D01*
X667822Y-291959D01*
X668622Y-291692D01*
X669222Y-291026D01*
X669622Y-290226D01*
X669922Y-289159D01*
X670022Y-287959D01*
X669922Y-286759D01*
X669622Y-285692D01*
X669222Y-284892D01*
X668622Y-284226D01*
X667822Y-283959D01*
G01X673922Y-291959D02*
Y-283959D01*
X677722D01*
G01X676322Y-287826D02*
X673922D01*
G01X683822Y-283959D02*
X683022Y-284226D01*
X682422Y-284892D01*
X682022Y-285692D01*
X681722Y-286759D01*
X681622Y-287959D01*
X681722Y-289159D01*
X682022Y-290226D01*
X682422Y-291026D01*
X683022Y-291692D01*
X683822Y-291959D01*
X684622Y-291692D01*
X685222Y-291026D01*
X685622Y-290226D01*
X685922Y-289159D01*
X686022Y-287959D01*
X685922Y-286759D01*
X685622Y-285692D01*
X685222Y-284892D01*
X684622Y-284226D01*
X683822Y-283959D01*
G01X691822D02*
Y-291959D01*
G01X689522Y-283959D02*
X694122D01*
G01X697922Y-291959D02*
Y-283959D01*
X701722D01*
G01X700322Y-287826D02*
X697922D01*
G01X708622Y-287692D02*
X709022Y-287292D01*
X709322Y-286626D01*
X709522Y-285692D01*
X709322Y-284892D01*
X708922Y-284359D01*
X708222Y-283959D01*
X705522D01*
Y-291959D01*
X708822D01*
X709522Y-291426D01*
X709922Y-290626D01*
X710122Y-289692D01*
X709922Y-288759D01*
X709322Y-287959D01*
X708622Y-287692D01*
X705522D01*
G01X713922Y-288626D02*
X714622Y-287692D01*
X715222Y-287159D01*
X716022Y-286892D01*
X716722Y-287159D01*
X717222Y-287692D01*
X717622Y-288492D01*
X717722Y-289426D01*
X717622Y-290226D01*
X717222Y-291026D01*
X716622Y-291692D01*
X715922Y-291959D01*
X715122Y-291692D01*
X714422Y-290893D01*
X714022Y-289692D01*
X713922Y-288359D01*
X714122Y-286626D01*
X714422Y-285692D01*
X714922Y-284759D01*
X715622Y-284092D01*
X716322Y-283959D01*
X717022Y-284226D01*
X717522Y-284892D01*
G01X721622Y-291959D02*
Y-283959D01*
X723622D01*
X724422Y-284359D01*
X725022Y-284892D01*
X725522Y-285692D01*
X725922Y-286626D01*
X726022Y-287959D01*
X725922Y-289292D01*
X725522Y-290226D01*
X725022Y-291026D01*
X724422Y-291559D01*
X723622Y-291959D01*
X721622D01*
G01X731822Y-283959D02*
X731022Y-284226D01*
X730422Y-284892D01*
X730022Y-285692D01*
X729722Y-286759D01*
X729622Y-287959D01*
X729722Y-289159D01*
X730022Y-290226D01*
X730422Y-291026D01*
X731022Y-291692D01*
X731822Y-291959D01*
X732622Y-291692D01*
X733222Y-291026D01*
X733622Y-290226D01*
X733922Y-289159D01*
X734022Y-287959D01*
X733922Y-286759D01*
X733622Y-285692D01*
X733222Y-284892D01*
X732622Y-284226D01*
X731822Y-283959D01*
G01X649862Y-270000D02*
Y-263700D01*
X652838D01*
G01X651742Y-266745D02*
X649862D01*
G01X657650Y-263700D02*
X657023Y-263910D01*
X656553Y-264435D01*
X656240Y-265065D01*
X656005Y-265905D01*
X655927Y-266850D01*
X656005Y-267795D01*
X656240Y-268635D01*
X656553Y-269265D01*
X657023Y-269790D01*
X657650Y-270000D01*
X658277Y-269790D01*
X658747Y-269265D01*
X659060Y-268635D01*
X659295Y-267795D01*
X659373Y-266850D01*
X659295Y-265905D01*
X659060Y-265065D01*
X658747Y-264435D01*
X658277Y-263910D01*
X657650Y-263700D01*
G01X663950D02*
Y-270000D01*
G01X662148Y-263700D02*
X665752D01*
G01X667900Y-272100D02*
X672600D01*
G01X674983Y-270000D02*
Y-263700D01*
X676863D01*
X677490Y-264015D01*
X677960Y-264750D01*
X678117Y-265590D01*
X677960Y-266430D01*
X677568Y-267060D01*
X676863Y-267375D01*
X674983D01*
G01X684573Y-264225D02*
X684103Y-263910D01*
X683555Y-263700D01*
X682928D01*
X682223Y-264015D01*
X681675Y-264540D01*
X681283Y-265170D01*
X680970Y-266220D01*
X680892Y-267165D01*
X681048Y-268110D01*
X681283Y-268740D01*
X681753Y-269370D01*
X682302Y-269790D01*
X682850Y-270000D01*
X683398D01*
X683947Y-269790D01*
X684417Y-269475D01*
X684808Y-269055D01*
G01X689777Y-266640D02*
X690090Y-266325D01*
X690325Y-265800D01*
X690482Y-265065D01*
X690325Y-264435D01*
X690012Y-264015D01*
X689463Y-263700D01*
X687348D01*
Y-270000D01*
X689933D01*
X690482Y-269580D01*
X690795Y-268950D01*
X690952Y-268215D01*
X690795Y-267480D01*
X690325Y-266850D01*
X689777Y-266640D01*
X687348D01*
G01X693100Y-272100D02*
X697800D01*
G01X700262Y-270000D02*
Y-263700D01*
X703238D01*
G01X702142Y-266745D02*
X700262D01*
G01X706092Y-270000D02*
X708050Y-263700D01*
X710008Y-270000D01*
G01X709303Y-267795D02*
X706797D01*
G01X712548Y-270000D02*
Y-263700D01*
X716152Y-270000D01*
Y-263700D01*
G01X718300Y-272100D02*
X723000D01*
G01X727577Y-266640D02*
X727890Y-266325D01*
X728125Y-265800D01*
X728282Y-265065D01*
X728125Y-264435D01*
X727812Y-264015D01*
X727263Y-263700D01*
X725148D01*
Y-270000D01*
X727733D01*
X728282Y-269580D01*
X728595Y-268950D01*
X728752Y-268215D01*
X728595Y-267480D01*
X728125Y-266850D01*
X727577Y-266640D01*
X725148D01*
G01X733250Y-270000D02*
X732623Y-269895D01*
X732075Y-269475D01*
X731605Y-268845D01*
X731292Y-268110D01*
X731135Y-267270D01*
Y-266430D01*
X731292Y-265590D01*
X731605Y-264855D01*
X732075Y-264225D01*
X732623Y-263805D01*
X733250Y-263700D01*
X733877Y-263805D01*
X734425Y-264225D01*
X734895Y-264855D01*
X735208Y-265590D01*
X735365Y-266430D01*
Y-267270D01*
X735208Y-268110D01*
X734895Y-268845D01*
X734425Y-269475D01*
X733877Y-269895D01*
X733250Y-270000D01*
G01X737592D02*
X739550Y-263700D01*
X741508Y-270000D01*
G01X740803Y-267795D02*
X738297D01*
G01X744283Y-270000D02*
Y-263700D01*
X746242D01*
X746868Y-264015D01*
X747260Y-264435D01*
X747417Y-265275D01*
X747260Y-266115D01*
X746790Y-266640D01*
X746242Y-266955D01*
X744283D01*
G01X746242D02*
X747417Y-270000D01*
G01X750427D02*
Y-263700D01*
X751993D01*
X752620Y-264015D01*
X753090Y-264435D01*
X753482Y-265065D01*
X753795Y-265800D01*
X753873Y-266850D01*
X753795Y-267900D01*
X753482Y-268635D01*
X753090Y-269265D01*
X752620Y-269685D01*
X751993Y-270000D01*
X750427D01*
G01X756100Y-272100D02*
X760800D01*
G01X762713Y-270000D02*
Y-263700D01*
X764750Y-268950D01*
X766787Y-263700D01*
Y-270000D01*
G01X769483D02*
Y-263700D01*
X771363D01*
X771990Y-264015D01*
X772460Y-264750D01*
X772617Y-265590D01*
X772460Y-266430D01*
X772068Y-267060D01*
X771363Y-267375D01*
X769483D01*
G01X775627Y-269055D02*
X776097Y-269580D01*
X776645Y-269895D01*
X777350Y-270000D01*
X778055Y-269790D01*
X778603Y-269370D01*
X778995Y-268635D01*
X779073Y-267795D01*
X778917Y-266955D01*
X778525Y-266430D01*
X777977Y-266010D01*
X777428Y-265905D01*
X776880Y-266010D01*
X776175Y-266430D01*
X776410Y-263700D01*
X778525D01*
G01X783650D02*
X783023Y-263910D01*
X782553Y-264435D01*
X782240Y-265065D01*
X782005Y-265905D01*
X781927Y-266850D01*
X782005Y-267795D01*
X782240Y-268635D01*
X782553Y-269265D01*
X783023Y-269790D01*
X783650Y-270000D01*
X784277Y-269790D01*
X784747Y-269265D01*
X785060Y-268635D01*
X785295Y-267795D01*
X785373Y-266850D01*
X785295Y-265905D01*
X785060Y-265065D01*
X784747Y-264435D01*
X784277Y-263910D01*
X783650Y-263700D01*
G01X790890Y-270000D02*
Y-263700D01*
X787992Y-268215D01*
X791908D01*
G01X796250Y-270000D02*
X796798Y-269895D01*
X797425Y-269580D01*
X797817Y-269055D01*
X797973Y-268320D01*
X797817Y-267585D01*
X797347Y-266955D01*
X796642Y-266640D01*
X795858D01*
X795388Y-266430D01*
X794997Y-265905D01*
X794840Y-265170D01*
X795075Y-264435D01*
X795623Y-263910D01*
X796250Y-263700D01*
X796877Y-263910D01*
X797425Y-264435D01*
X797660Y-265170D01*
X797503Y-265905D01*
X797112Y-266430D01*
X796642Y-266640D01*
X795858D01*
X795153Y-266955D01*
X794683Y-267585D01*
X794527Y-268320D01*
X794683Y-269055D01*
X795075Y-269580D01*
X795702Y-269895D01*
X796250Y-270000D01*
G01X738322Y-319959D02*
Y-311959D01*
X737122Y-313559D01*
G01Y-319959D02*
X739522D01*
G01X744422Y-316626D02*
X745122Y-315692D01*
X745722Y-315159D01*
X746522Y-314892D01*
X747222Y-315159D01*
X747722Y-315692D01*
X748122Y-316492D01*
X748222Y-317426D01*
X748122Y-318226D01*
X747722Y-319026D01*
X747122Y-319692D01*
X746422Y-319959D01*
X745622Y-319692D01*
X744922Y-318893D01*
X744522Y-317692D01*
X744422Y-316359D01*
X744622Y-314626D01*
X744922Y-313692D01*
X745422Y-312759D01*
X746122Y-312092D01*
X746822Y-311959D01*
X747522Y-312226D01*
X748022Y-312892D01*
G01X754322Y-320226D02*
X754122Y-320092D01*
Y-319826D01*
X754322Y-319692D01*
X754522Y-319826D01*
Y-320092D01*
X754322Y-320226D01*
G01X760422Y-316626D02*
X761122Y-315692D01*
X761722Y-315159D01*
X762522Y-314892D01*
X763222Y-315159D01*
X763722Y-315692D01*
X764122Y-316492D01*
X764222Y-317426D01*
X764122Y-318226D01*
X763722Y-319026D01*
X763122Y-319692D01*
X762422Y-319959D01*
X761622Y-319692D01*
X760922Y-318893D01*
X760522Y-317692D01*
X760422Y-316359D01*
X760622Y-314626D01*
X760922Y-313692D01*
X761422Y-312759D01*
X762122Y-312092D01*
X762822Y-311959D01*
X763522Y-312226D01*
X764022Y-312892D01*
G01X783322Y-319959D02*
Y-311959D01*
X782122Y-313559D01*
G01Y-319959D02*
X784522D01*
G01X791122D02*
X791322Y-318226D01*
X791622Y-316759D01*
X792022Y-315426D01*
X792522Y-313959D01*
X793322Y-311959D01*
X789322D01*
G01X799322Y-320226D02*
X799122Y-320092D01*
Y-319826D01*
X799322Y-319692D01*
X799522Y-319826D01*
Y-320092D01*
X799322Y-320226D01*
G01X805422Y-313292D02*
X806022Y-312492D01*
X806722Y-312092D01*
X807522Y-311959D01*
X808522Y-312226D01*
X809222Y-312892D01*
X809422Y-313692D01*
X809322Y-314493D01*
X808922Y-315159D01*
X806922Y-316492D01*
X806022Y-317426D01*
X805422Y-318759D01*
X805222Y-319959D01*
X809422D01*
G01X803122Y-294959D02*
Y-286959D01*
X805122D01*
X805922Y-287359D01*
X806522Y-287892D01*
X807022Y-288692D01*
X807422Y-289626D01*
X807522Y-290959D01*
X807422Y-292292D01*
X807022Y-293226D01*
X806522Y-294026D01*
X805922Y-294559D01*
X805122Y-294959D01*
X803122D01*
M02*
